(kicad_sch (version 20211123) (generator eeschema)

  (paper "A3")

  (title_block
    (title "SA800U (Snapdragon 845) Baseboard")
    (date "2023-10-19")
    (rev "1.0.3")
    (company "Antmicro Ltd.")
    (comment 1 "www.antmicro.com")
  )

  (junction (at 122.555 236.22) (diameter 0) (color 0 0 0 0)
  )
  (junction (at 111.125 228.6) (diameter 0) (color 0 0 0 0)
  )
  (junction (at 119.38 60.325) (diameter 0) (color 0 0 0 0)
  )
  (junction (at 158.115 253.365) (diameter 0) (color 0 0 0 0)
  )
  (junction (at 135.255 46.99) (diameter 0) (color 0 0 0 0)
  )
  (junction (at 158.115 263.525) (diameter 0) (color 0 0 0 0)
  )
  (junction (at 317.5 97.79) (diameter 0) (color 0 0 0 0)
  )
  (junction (at 113.665 253.365) (diameter 0) (color 0 0 0 0)
  )
  (junction (at 160.655 241.3) (diameter 0) (color 0 0 0 0)
  )
  (junction (at 113.665 228.6) (diameter 0) (color 0 0 0 0)
  )
  (junction (at 111.125 253.365) (diameter 0) (color 0 0 0 0)
  )
  (junction (at 312.42 148.59) (diameter 0) (color 0 0 0 0)
  )
  (junction (at 113.665 263.525) (diameter 0) (color 0 0 0 0)
  )
  (junction (at 316.23 153.67) (diameter 0) (color 0 0 0 0)
  )
  (junction (at 317.5 143.51) (diameter 0) (color 0 0 0 0)
  )
  (junction (at 317.5 135.89) (diameter 0) (color 0 0 0 0)
  )
  (junction (at 111.125 266.065) (diameter 0) (color 0 0 0 0)
  )
  (junction (at 122.555 260.985) (diameter 0) (color 0 0 0 0)
  )
  (junction (at 158.115 238.76) (diameter 0) (color 0 0 0 0)
  )
  (junction (at 309.245 151.13) (diameter 0) (color 0 0 0 0)
  )
  (junction (at 181.61 253.365) (diameter 0) (color 0 0 0 0)
  )
  (junction (at 135.255 47.117) (diameter 0) (color 0 0 0 0)
  )
  (junction (at 160.655 266.065) (diameter 0) (color 0 0 0 0)
  )
  (junction (at 111.125 241.3) (diameter 0) (color 0 0 0 0)
  )
  (junction (at 90.17 228.6) (diameter 0) (color 0 0 0 0)
  )
  (junction (at 320.04 191.77) (diameter 0) (color 0 0 0 0)
  )
  (junction (at 181.61 228.6) (diameter 0) (color 0 0 0 0)
  )
  (junction (at 160.655 228.6) (diameter 0) (color 0 0 0 0)
  )
  (junction (at 113.665 238.76) (diameter 0) (color 0 0 0 0)
  )
  (junction (at 158.115 228.6) (diameter 0) (color 0 0 0 0)
  )
  (junction (at 87.757 60.325) (diameter 0) (color 0 0 0 0)
  )
  (junction (at 317.5 113.03) (diameter 0) (color 0 0 0 0)
  )
  (junction (at 160.655 253.365) (diameter 0) (color 0 0 0 0)
  )
  (junction (at 320.04 186.69) (diameter 0) (color 0 0 0 0)
  )
  (junction (at 90.17 253.365) (diameter 0) (color 0 0 0 0)
  )
  (junction (at 317.5 105.41) (diameter 0) (color 0 0 0 0)
  )

  (no_connect (at 321.31 176.53))
  (no_connect (at 321.31 179.07))
  (no_connect (at 321.31 196.85))
  (no_connect (at 321.31 110.49))
  (no_connect (at 321.31 163.83))
  (no_connect (at 321.31 102.87))
  (no_connect (at 321.31 100.33))
  (no_connect (at 321.31 199.39))
  (no_connect (at 321.31 107.95))
  (no_connect (at 321.31 156.21))
  (no_connect (at 321.31 158.75))
  (no_connect (at 321.31 181.61))
  (no_connect (at 321.31 146.05))
  (no_connect (at 321.31 161.29))
  (no_connect (at 321.31 184.15))

  (wire (pts (xy 158.115 230.759) (xy 158.115 228.6))
    (stroke (width 0) (type default) (color 0 0 0 0))
  )
  (wire (pts (xy 181.61 227.838) (xy 181.61 228.6))
    (stroke (width 0) (type default) (color 0 0 0 0))
  )
  (wire (pts (xy 106.045 196.85) (xy 123.19 196.85))
    (stroke (width 0) (type default) (color 0 0 0 0))
  )
  (wire (pts (xy 87.757 60.325) (xy 87.757 64.135))
    (stroke (width 0) (type default) (color 0 0 0 0))
  )
  (wire (pts (xy 90.805 194.31) (xy 90.805 193.04))
    (stroke (width 0) (type default) (color 0 0 0 0))
  )
  (wire (pts (xy 317.5 90.17) (xy 317.5 97.79))
    (stroke (width 0) (type default) (color 0 0 0 0))
  )
  (wire (pts (xy 111.125 241.3) (xy 125.73 241.3))
    (stroke (width 0) (type default) (color 0 0 0 0))
  )
  (wire (pts (xy 321.31 80.01) (xy 295.91 80.01))
    (stroke (width 0) (type default) (color 0 0 0 0))
  )
  (wire (pts (xy 105.664 133.096) (xy 105.664 131.826))
    (stroke (width 0) (type default) (color 0 0 0 0))
  )
  (wire (pts (xy 105.664 106.426) (xy 123.444 106.426))
    (stroke (width 0) (type default) (color 0 0 0 0))
  )
  (wire (pts (xy 111.125 253.365) (xy 113.665 253.365))
    (stroke (width 0) (type default) (color 0 0 0 0))
  )
  (wire (pts (xy 113.665 228.6) (xy 122.555 228.6))
    (stroke (width 0) (type default) (color 0 0 0 0))
  )
  (wire (pts (xy 122.555 243.84) (xy 122.555 236.22))
    (stroke (width 0) (type default) (color 0 0 0 0))
  )
  (wire (pts (xy 90.805 182.88) (xy 84.455 182.88))
    (stroke (width 0) (type default) (color 0 0 0 0))
  )
  (wire (pts (xy 321.31 194.31) (xy 320.04 194.31))
    (stroke (width 0) (type default) (color 0 0 0 0))
  )
  (wire (pts (xy 309.245 151.13) (xy 306.705 151.13))
    (stroke (width 0) (type default) (color 0 0 0 0))
  )
  (wire (pts (xy 106.045 205.74) (xy 123.19 205.74))
    (stroke (width 0) (type default) (color 0 0 0 0))
  )
  (wire (pts (xy 113.665 260.223) (xy 113.665 263.525))
    (stroke (width 0) (type default) (color 0 0 0 0))
  )
  (wire (pts (xy 295.91 168.91) (xy 321.31 168.91))
    (stroke (width 0) (type default) (color 0 0 0 0))
  )
  (wire (pts (xy 135.255 46.99) (xy 154.305 46.99))
    (stroke (width 0) (type default) (color 0 0 0 0))
  )
  (wire (pts (xy 90.424 108.966) (xy 90.424 110.236))
    (stroke (width 0) (type default) (color 0 0 0 0))
  )
  (wire (pts (xy 105.664 143.256) (xy 123.444 143.256))
    (stroke (width 0) (type default) (color 0 0 0 0))
  )
  (wire (pts (xy 312.42 147.955) (xy 312.42 148.59))
    (stroke (width 0) (type default) (color 0 0 0 0))
  )
  (wire (pts (xy 135.255 45.593) (xy 135.255 46.99))
    (stroke (width 0) (type default) (color 0 0 0 0))
  )
  (wire (pts (xy 84.074 106.426) (xy 90.424 106.426))
    (stroke (width 0) (type default) (color 0 0 0 0))
  )
  (wire (pts (xy 160.655 228.6) (xy 181.61 228.6))
    (stroke (width 0) (type default) (color 0 0 0 0))
  )
  (wire (pts (xy 181.61 228.6) (xy 181.61 229.87))
    (stroke (width 0) (type default) (color 0 0 0 0))
  )
  (wire (pts (xy 295.91 125.73) (xy 321.31 125.73))
    (stroke (width 0) (type default) (color 0 0 0 0))
  )
  (wire (pts (xy 295.91 140.97) (xy 321.31 140.97))
    (stroke (width 0) (type default) (color 0 0 0 0))
  )
  (wire (pts (xy 111.125 231.267) (xy 111.125 228.6))
    (stroke (width 0) (type default) (color 0 0 0 0))
  )
  (wire (pts (xy 84.455 194.31) (xy 90.805 194.31))
    (stroke (width 0) (type default) (color 0 0 0 0))
  )
  (wire (pts (xy 106.045 173.99) (xy 123.19 173.99))
    (stroke (width 0) (type default) (color 0 0 0 0))
  )
  (wire (pts (xy 90.805 185.42) (xy 90.805 186.69))
    (stroke (width 0) (type default) (color 0 0 0 0))
  )
  (wire (pts (xy 146.05 268.605) (xy 147.32 268.605))
    (stroke (width 0) (type default) (color 0 0 0 0))
  )
  (wire (pts (xy 321.31 92.71) (xy 295.91 92.71))
    (stroke (width 0) (type default) (color 0 0 0 0))
  )
  (wire (pts (xy 146.05 238.76) (xy 158.115 238.76))
    (stroke (width 0) (type default) (color 0 0 0 0))
  )
  (wire (pts (xy 149.225 228.6) (xy 149.225 236.22))
    (stroke (width 0) (type default) (color 0 0 0 0))
  )
  (polyline (pts (xy 167.005 80.01) (xy 71.755 80.01))
    (stroke (width 0) (type default) (color 0 0 0 0))
  )

  (wire (pts (xy 105.664 117.856) (xy 123.444 117.856))
    (stroke (width 0) (type default) (color 0 0 0 0))
  )
  (wire (pts (xy 158.115 235.839) (xy 158.115 238.76))
    (stroke (width 0) (type default) (color 0 0 0 0))
  )
  (wire (pts (xy 90.805 160.02) (xy 84.455 160.02))
    (stroke (width 0) (type default) (color 0 0 0 0))
  )
  (wire (pts (xy 160.655 235.839) (xy 160.655 241.3))
    (stroke (width 0) (type default) (color 0 0 0 0))
  )
  (wire (pts (xy 122.555 236.22) (xy 125.73 236.22))
    (stroke (width 0) (type default) (color 0 0 0 0))
  )
  (wire (pts (xy 158.115 263.525) (xy 179.07 263.525))
    (stroke (width 0) (type default) (color 0 0 0 0))
  )
  (wire (pts (xy 90.424 117.856) (xy 84.074 117.856))
    (stroke (width 0) (type default) (color 0 0 0 0))
  )
  (wire (pts (xy 90.424 129.286) (xy 90.424 128.016))
    (stroke (width 0) (type default) (color 0 0 0 0))
  )
  (wire (pts (xy 90.805 198.12) (xy 90.805 196.85))
    (stroke (width 0) (type default) (color 0 0 0 0))
  )
  (wire (pts (xy 160.655 268.605) (xy 160.655 266.065))
    (stroke (width 0) (type default) (color 0 0 0 0))
  )
  (wire (pts (xy 147.32 268.605) (xy 147.32 269.875))
    (stroke (width 0) (type default) (color 0 0 0 0))
  )
  (wire (pts (xy 320.04 194.31) (xy 320.04 191.77))
    (stroke (width 0) (type default) (color 0 0 0 0))
  )
  (wire (pts (xy 90.424 140.716) (xy 90.424 139.446))
    (stroke (width 0) (type default) (color 0 0 0 0))
  )
  (wire (pts (xy 119.38 53.34) (xy 119.38 60.325))
    (stroke (width 0) (type default) (color 0 0 0 0))
  )
  (wire (pts (xy 135.255 46.99) (xy 135.255 47.117))
    (stroke (width 0) (type default) (color 0 0 0 0))
  )
  (wire (pts (xy 295.91 133.35) (xy 321.31 133.35))
    (stroke (width 0) (type default) (color 0 0 0 0))
  )
  (wire (pts (xy 106.045 162.56) (xy 123.19 162.56))
    (stroke (width 0) (type default) (color 0 0 0 0))
  )
  (wire (pts (xy 181.61 253.365) (xy 181.61 254.762))
    (stroke (width 0) (type default) (color 0 0 0 0))
  )
  (wire (pts (xy 113.665 255.143) (xy 113.665 253.365))
    (stroke (width 0) (type default) (color 0 0 0 0))
  )
  (wire (pts (xy 146.05 263.525) (xy 158.115 263.525))
    (stroke (width 0) (type default) (color 0 0 0 0))
  )
  (wire (pts (xy 111.125 228.6) (xy 113.665 228.6))
    (stroke (width 0) (type default) (color 0 0 0 0))
  )
  (wire (pts (xy 106.045 204.47) (xy 106.045 205.74))
    (stroke (width 0) (type default) (color 0 0 0 0))
  )
  (wire (pts (xy 160.655 253.365) (xy 181.61 253.365))
    (stroke (width 0) (type default) (color 0 0 0 0))
  )
  (wire (pts (xy 111.125 268.605) (xy 111.125 266.065))
    (stroke (width 0) (type default) (color 0 0 0 0))
  )
  (wire (pts (xy 317.5 135.89) (xy 317.5 143.51))
    (stroke (width 0) (type default) (color 0 0 0 0))
  )
  (wire (pts (xy 160.655 243.84) (xy 160.655 241.3))
    (stroke (width 0) (type default) (color 0 0 0 0))
  )
  (wire (pts (xy 105.664 131.826) (xy 123.444 131.826))
    (stroke (width 0) (type default) (color 0 0 0 0))
  )
  (wire (pts (xy 158.115 253.365) (xy 160.655 253.365))
    (stroke (width 0) (type default) (color 0 0 0 0))
  )
  (wire (pts (xy 111.125 266.065) (xy 107.315 266.065))
    (stroke (width 0) (type default) (color 0 0 0 0))
  )
  (wire (pts (xy 113.665 238.76) (xy 125.73 238.76))
    (stroke (width 0) (type default) (color 0 0 0 0))
  )
  (wire (pts (xy 113.665 243.84) (xy 113.665 238.76))
    (stroke (width 0) (type default) (color 0 0 0 0))
  )
  (wire (pts (xy 113.665 231.267) (xy 113.665 228.6))
    (stroke (width 0) (type default) (color 0 0 0 0))
  )
  (wire (pts (xy 105.664 108.966) (xy 123.444 108.966))
    (stroke (width 0) (type default) (color 0 0 0 0))
  )
  (wire (pts (xy 160.655 266.065) (xy 179.07 266.065))
    (stroke (width 0) (type default) (color 0 0 0 0))
  )
  (wire (pts (xy 90.805 196.85) (xy 84.455 196.85))
    (stroke (width 0) (type default) (color 0 0 0 0))
  )
  (wire (pts (xy 158.115 260.731) (xy 158.115 263.525))
    (stroke (width 0) (type default) (color 0 0 0 0))
  )
  (wire (pts (xy 106.045 185.42) (xy 123.19 185.42))
    (stroke (width 0) (type default) (color 0 0 0 0))
  )
  (wire (pts (xy 105.664 98.806) (xy 105.664 97.536))
    (stroke (width 0) (type default) (color 0 0 0 0))
  )
  (wire (pts (xy 84.074 140.716) (xy 90.424 140.716))
    (stroke (width 0) (type default) (color 0 0 0 0))
  )
  (wire (pts (xy 321.31 105.41) (xy 317.5 105.41))
    (stroke (width 0) (type default) (color 0 0 0 0))
  )
  (wire (pts (xy 312.42 148.59) (xy 308.61 148.59))
    (stroke (width 0) (type default) (color 0 0 0 0))
  )
  (wire (pts (xy 295.91 123.19) (xy 321.31 123.19))
    (stroke (width 0) (type default) (color 0 0 0 0))
  )
  (wire (pts (xy 295.91 120.65) (xy 321.31 120.65))
    (stroke (width 0) (type default) (color 0 0 0 0))
  )
  (wire (pts (xy 106.045 198.12) (xy 106.045 196.85))
    (stroke (width 0) (type default) (color 0 0 0 0))
  )
  (wire (pts (xy 160.655 241.3) (xy 179.07 241.3))
    (stroke (width 0) (type default) (color 0 0 0 0))
  )
  (wire (pts (xy 105.664 105.156) (xy 105.664 106.426))
    (stroke (width 0) (type default) (color 0 0 0 0))
  )
  (wire (pts (xy 316.23 154.94) (xy 316.23 153.67))
    (stroke (width 0) (type default) (color 0 0 0 0))
  )
  (wire (pts (xy 317.5 97.79) (xy 317.5 105.41))
    (stroke (width 0) (type default) (color 0 0 0 0))
  )
  (wire (pts (xy 90.805 162.56) (xy 84.455 162.56))
    (stroke (width 0) (type default) (color 0 0 0 0))
  )
  (wire (pts (xy 295.91 87.63) (xy 321.31 87.63))
    (stroke (width 0) (type default) (color 0 0 0 0))
  )
  (wire (pts (xy 113.665 236.347) (xy 113.665 238.76))
    (stroke (width 0) (type default) (color 0 0 0 0))
  )
  (wire (pts (xy 105.664 121.666) (xy 105.664 120.396))
    (stroke (width 0) (type default) (color 0 0 0 0))
  )
  (wire (pts (xy 317.5 113.03) (xy 317.5 135.89))
    (stroke (width 0) (type default) (color 0 0 0 0))
  )
  (wire (pts (xy 321.31 135.89) (xy 317.5 135.89))
    (stroke (width 0) (type default) (color 0 0 0 0))
  )
  (wire (pts (xy 122.555 260.985) (xy 125.73 260.985))
    (stroke (width 0) (type default) (color 0 0 0 0))
  )
  (wire (pts (xy 122.555 268.605) (xy 122.555 260.985))
    (stroke (width 0) (type default) (color 0 0 0 0))
  )
  (wire (pts (xy 321.31 90.17) (xy 317.5 90.17))
    (stroke (width 0) (type default) (color 0 0 0 0))
  )
  (wire (pts (xy 90.805 209.55) (xy 90.805 208.28))
    (stroke (width 0) (type default) (color 0 0 0 0))
  )
  (wire (pts (xy 113.665 268.605) (xy 113.665 263.525))
    (stroke (width 0) (type default) (color 0 0 0 0))
  )
  (wire (pts (xy 84.074 108.966) (xy 90.424 108.966))
    (stroke (width 0) (type default) (color 0 0 0 0))
  )
  (wire (pts (xy 90.805 158.75) (xy 90.805 160.02))
    (stroke (width 0) (type default) (color 0 0 0 0))
  )
  (wire (pts (xy 105.664 116.586) (xy 105.664 117.856))
    (stroke (width 0) (type default) (color 0 0 0 0))
  )
  (wire (pts (xy 320.04 186.69) (xy 321.31 186.69))
    (stroke (width 0) (type default) (color 0 0 0 0))
  )
  (wire (pts (xy 90.805 173.99) (xy 90.805 175.26))
    (stroke (width 0) (type default) (color 0 0 0 0))
  )
  (wire (pts (xy 84.455 205.74) (xy 90.805 205.74))
    (stroke (width 0) (type default) (color 0 0 0 0))
  )
  (wire (pts (xy 106.045 193.04) (xy 106.045 194.31))
    (stroke (width 0) (type default) (color 0 0 0 0))
  )
  (wire (pts (xy 87.757 60.325) (xy 86.487 60.325))
    (stroke (width 0) (type default) (color 0 0 0 0))
  )
  (wire (pts (xy 106.045 170.18) (xy 106.045 171.45))
    (stroke (width 0) (type default) (color 0 0 0 0))
  )
  (wire (pts (xy 158.115 238.76) (xy 179.07 238.76))
    (stroke (width 0) (type default) (color 0 0 0 0))
  )
  (wire (pts (xy 295.91 173.99) (xy 321.31 173.99))
    (stroke (width 0) (type default) (color 0 0 0 0))
  )
  (wire (pts (xy 105.664 93.726) (xy 105.664 94.996))
    (stroke (width 0) (type default) (color 0 0 0 0))
  )
  (wire (pts (xy 119.38 60.325) (xy 119.38 61.595))
    (stroke (width 0) (type default) (color 0 0 0 0))
  )
  (wire (pts (xy 83.82 228.6) (xy 90.17 228.6))
    (stroke (width 0) (type default) (color 0 0 0 0))
  )
  (wire (pts (xy 106.045 160.02) (xy 123.19 160.02))
    (stroke (width 0) (type default) (color 0 0 0 0))
  )
  (wire (pts (xy 105.664 97.536) (xy 123.444 97.536))
    (stroke (width 0) (type default) (color 0 0 0 0))
  )
  (wire (pts (xy 295.91 118.11) (xy 321.31 118.11))
    (stroke (width 0) (type default) (color 0 0 0 0))
  )
  (wire (pts (xy 90.805 163.83) (xy 90.805 162.56))
    (stroke (width 0) (type default) (color 0 0 0 0))
  )
  (wire (pts (xy 160.655 255.651) (xy 160.655 253.365))
    (stroke (width 0) (type default) (color 0 0 0 0))
  )
  (wire (pts (xy 321.31 143.51) (xy 317.5 143.51))
    (stroke (width 0) (type default) (color 0 0 0 0))
  )
  (wire (pts (xy 83.82 253.365) (xy 90.17 253.365))
    (stroke (width 0) (type default) (color 0 0 0 0))
  )
  (wire (pts (xy 90.424 94.996) (xy 84.074 94.996))
    (stroke (width 0) (type default) (color 0 0 0 0))
  )
  (wire (pts (xy 321.31 151.13) (xy 309.245 151.13))
    (stroke (width 0) (type default) (color 0 0 0 0))
  )
  (wire (pts (xy 105.664 139.446) (xy 105.664 140.716))
    (stroke (width 0) (type default) (color 0 0 0 0))
  )
  (wire (pts (xy 192.405 253.365) (xy 181.61 253.365))
    (stroke (width 0) (type default) (color 0 0 0 0))
  )
  (wire (pts (xy 106.045 158.75) (xy 106.045 160.02))
    (stroke (width 0) (type default) (color 0 0 0 0))
  )
  (wire (pts (xy 320.04 189.23) (xy 320.04 186.69))
    (stroke (width 0) (type default) (color 0 0 0 0))
  )
  (wire (pts (xy 295.91 171.45) (xy 321.31 171.45))
    (stroke (width 0) (type default) (color 0 0 0 0))
  )
  (wire (pts (xy 113.665 253.365) (xy 122.555 253.365))
    (stroke (width 0) (type default) (color 0 0 0 0))
  )
  (wire (pts (xy 90.424 144.526) (xy 90.424 143.256))
    (stroke (width 0) (type default) (color 0 0 0 0))
  )
  (wire (pts (xy 321.31 113.03) (xy 317.5 113.03))
    (stroke (width 0) (type default) (color 0 0 0 0))
  )
  (wire (pts (xy 295.91 186.69) (xy 320.04 186.69))
    (stroke (width 0) (type default) (color 0 0 0 0))
  )
  (wire (pts (xy 321.31 189.23) (xy 320.04 189.23))
    (stroke (width 0) (type default) (color 0 0 0 0))
  )
  (wire (pts (xy 90.17 253.365) (xy 90.17 254.635))
    (stroke (width 0) (type default) (color 0 0 0 0))
  )
  (wire (pts (xy 160.655 260.731) (xy 160.655 266.065))
    (stroke (width 0) (type default) (color 0 0 0 0))
  )
  (wire (pts (xy 181.61 228.6) (xy 191.77 228.6))
    (stroke (width 0) (type default) (color 0 0 0 0))
  )
  (wire (pts (xy 106.045 182.88) (xy 123.19 182.88))
    (stroke (width 0) (type default) (color 0 0 0 0))
  )
  (wire (pts (xy 122.555 243.84) (xy 125.73 243.84))
    (stroke (width 0) (type default) (color 0 0 0 0))
  )
  (wire (pts (xy 122.555 253.365) (xy 122.555 260.985))
    (stroke (width 0) (type default) (color 0 0 0 0))
  )
  (wire (pts (xy 90.424 106.426) (xy 90.424 105.156))
    (stroke (width 0) (type default) (color 0 0 0 0))
  )
  (wire (pts (xy 149.225 253.365) (xy 149.225 260.985))
    (stroke (width 0) (type default) (color 0 0 0 0))
  )
  (polyline (pts (xy 71.755 22.86) (xy 167.005 22.86))
    (stroke (width 0) (type default) (color 0 0 0 0))
  )

  (wire (pts (xy 295.91 74.93) (xy 321.31 74.93))
    (stroke (width 0) (type default) (color 0 0 0 0))
  )
  (wire (pts (xy 105.664 94.996) (xy 123.444 94.996))
    (stroke (width 0) (type default) (color 0 0 0 0))
  )
  (wire (pts (xy 105.664 144.526) (xy 105.664 143.256))
    (stroke (width 0) (type default) (color 0 0 0 0))
  )
  (wire (pts (xy 90.17 253.365) (xy 111.125 253.365))
    (stroke (width 0) (type default) (color 0 0 0 0))
  )
  (wire (pts (xy 105.664 129.286) (xy 123.444 129.286))
    (stroke (width 0) (type default) (color 0 0 0 0))
  )
  (wire (pts (xy 321.31 153.67) (xy 316.23 153.67))
    (stroke (width 0) (type default) (color 0 0 0 0))
  )
  (wire (pts (xy 91.44 34.29) (xy 135.255 34.29))
    (stroke (width 0) (type default) (color 0 0 0 0))
  )
  (wire (pts (xy 106.045 194.31) (xy 123.19 194.31))
    (stroke (width 0) (type default) (color 0 0 0 0))
  )
  (wire (pts (xy 90.424 131.826) (xy 84.074 131.826))
    (stroke (width 0) (type default) (color 0 0 0 0))
  )
  (wire (pts (xy 106.045 208.28) (xy 123.19 208.28))
    (stroke (width 0) (type default) (color 0 0 0 0))
  )
  (wire (pts (xy 105.664 120.396) (xy 123.444 120.396))
    (stroke (width 0) (type default) (color 0 0 0 0))
  )
  (wire (pts (xy 160.655 230.759) (xy 160.655 228.6))
    (stroke (width 0) (type default) (color 0 0 0 0))
  )
  (wire (pts (xy 106.045 171.45) (xy 123.19 171.45))
    (stroke (width 0) (type default) (color 0 0 0 0))
  )
  (wire (pts (xy 87.757 60.325) (xy 100.965 60.325))
    (stroke (width 0) (type default) (color 0 0 0 0))
  )
  (wire (pts (xy 84.455 185.42) (xy 90.805 185.42))
    (stroke (width 0) (type default) (color 0 0 0 0))
  )
  (wire (pts (xy 105.664 140.716) (xy 123.444 140.716))
    (stroke (width 0) (type default) (color 0 0 0 0))
  )
  (wire (pts (xy 147.32 243.84) (xy 147.32 245.11))
    (stroke (width 0) (type default) (color 0 0 0 0))
  )
  (wire (pts (xy 106.045 175.26) (xy 106.045 173.99))
    (stroke (width 0) (type default) (color 0 0 0 0))
  )
  (wire (pts (xy 317.5 105.41) (xy 317.5 113.03))
    (stroke (width 0) (type default) (color 0 0 0 0))
  )
  (wire (pts (xy 135.255 34.29) (xy 135.255 40.513))
    (stroke (width 0) (type default) (color 0 0 0 0))
  )
  (wire (pts (xy 295.91 77.47) (xy 321.31 77.47))
    (stroke (width 0) (type default) (color 0 0 0 0))
  )
  (wire (pts (xy 295.91 115.57) (xy 321.31 115.57))
    (stroke (width 0) (type default) (color 0 0 0 0))
  )
  (wire (pts (xy 107.315 238.76) (xy 113.665 238.76))
    (stroke (width 0) (type default) (color 0 0 0 0))
  )
  (wire (pts (xy 111.125 241.3) (xy 107.315 241.3))
    (stroke (width 0) (type default) (color 0 0 0 0))
  )
  (wire (pts (xy 90.805 171.45) (xy 90.805 170.18))
    (stroke (width 0) (type default) (color 0 0 0 0))
  )
  (wire (pts (xy 304.165 191.77) (xy 320.04 191.77))
    (stroke (width 0) (type default) (color 0 0 0 0))
  )
  (wire (pts (xy 111.125 260.223) (xy 111.125 266.065))
    (stroke (width 0) (type default) (color 0 0 0 0))
  )
  (wire (pts (xy 90.424 120.396) (xy 90.424 121.666))
    (stroke (width 0) (type default) (color 0 0 0 0))
  )
  (wire (pts (xy 295.91 72.39) (xy 321.31 72.39))
    (stroke (width 0) (type default) (color 0 0 0 0))
  )
  (wire (pts (xy 100.965 62.865) (xy 99.441 62.865))
    (stroke (width 0) (type default) (color 0 0 0 0))
  )
  (wire (pts (xy 106.045 163.83) (xy 106.045 162.56))
    (stroke (width 0) (type default) (color 0 0 0 0))
  )
  (wire (pts (xy 113.665 263.525) (xy 125.73 263.525))
    (stroke (width 0) (type default) (color 0 0 0 0))
  )
  (wire (pts (xy 295.91 138.43) (xy 321.31 138.43))
    (stroke (width 0) (type default) (color 0 0 0 0))
  )
  (wire (pts (xy 84.455 173.99) (xy 90.805 173.99))
    (stroke (width 0) (type default) (color 0 0 0 0))
  )
  (wire (pts (xy 84.074 120.396) (xy 90.424 120.396))
    (stroke (width 0) (type default) (color 0 0 0 0))
  )
  (wire (pts (xy 107.315 263.525) (xy 113.665 263.525))
    (stroke (width 0) (type default) (color 0 0 0 0))
  )
  (wire (pts (xy 149.225 253.365) (xy 158.115 253.365))
    (stroke (width 0) (type default) (color 0 0 0 0))
  )
  (wire (pts (xy 135.255 60.325) (xy 135.255 53.213))
    (stroke (width 0) (type default) (color 0 0 0 0))
  )
  (wire (pts (xy 158.115 243.84) (xy 158.115 238.76))
    (stroke (width 0) (type default) (color 0 0 0 0))
  )
  (wire (pts (xy 135.255 48.133) (xy 135.255 47.117))
    (stroke (width 0) (type default) (color 0 0 0 0))
  )
  (wire (pts (xy 84.455 171.45) (xy 90.805 171.45))
    (stroke (width 0) (type default) (color 0 0 0 0))
  )
  (wire (pts (xy 321.31 82.55) (xy 295.91 82.55))
    (stroke (width 0) (type default) (color 0 0 0 0))
  )
  (wire (pts (xy 105.664 110.236) (xy 105.664 108.966))
    (stroke (width 0) (type default) (color 0 0 0 0))
  )
  (wire (pts (xy 146.05 243.84) (xy 147.32 243.84))
    (stroke (width 0) (type default) (color 0 0 0 0))
  )
  (wire (pts (xy 146.05 266.065) (xy 160.655 266.065))
    (stroke (width 0) (type default) (color 0 0 0 0))
  )
  (wire (pts (xy 317.5 143.51) (xy 317.5 204.47))
    (stroke (width 0) (type default) (color 0 0 0 0))
  )
  (polyline (pts (xy 167.005 22.86) (xy 167.005 80.01))
    (stroke (width 0) (type default) (color 0 0 0 0))
  )

  (wire (pts (xy 309.245 154.94) (xy 309.245 151.13))
    (stroke (width 0) (type default) (color 0 0 0 0))
  )
  (wire (pts (xy 111.125 236.347) (xy 111.125 241.3))
    (stroke (width 0) (type default) (color 0 0 0 0))
  )
  (wire (pts (xy 90.424 93.726) (xy 90.424 94.996))
    (stroke (width 0) (type default) (color 0 0 0 0))
  )
  (wire (pts (xy 119.38 60.325) (xy 135.255 60.325))
    (stroke (width 0) (type default) (color 0 0 0 0))
  )
  (wire (pts (xy 295.91 130.81) (xy 321.31 130.81))
    (stroke (width 0) (type default) (color 0 0 0 0))
  )
  (wire (pts (xy 122.555 228.6) (xy 122.555 236.22))
    (stroke (width 0) (type default) (color 0 0 0 0))
  )
  (wire (pts (xy 295.91 128.27) (xy 321.31 128.27))
    (stroke (width 0) (type default) (color 0 0 0 0))
  )
  (wire (pts (xy 125.73 268.605) (xy 122.555 268.605))
    (stroke (width 0) (type default) (color 0 0 0 0))
  )
  (wire (pts (xy 90.424 133.096) (xy 90.424 131.826))
    (stroke (width 0) (type default) (color 0 0 0 0))
  )
  (polyline (pts (xy 71.755 80.01) (xy 71.755 22.86))
    (stroke (width 0) (type default) (color 0 0 0 0))
  )

  (wire (pts (xy 321.31 148.59) (xy 312.42 148.59))
    (stroke (width 0) (type default) (color 0 0 0 0))
  )
  (wire (pts (xy 90.805 181.61) (xy 90.805 182.88))
    (stroke (width 0) (type default) (color 0 0 0 0))
  )
  (wire (pts (xy 111.125 243.84) (xy 111.125 241.3))
    (stroke (width 0) (type default) (color 0 0 0 0))
  )
  (wire (pts (xy 106.045 209.55) (xy 106.045 208.28))
    (stroke (width 0) (type default) (color 0 0 0 0))
  )
  (wire (pts (xy 90.805 208.28) (xy 84.455 208.28))
    (stroke (width 0) (type default) (color 0 0 0 0))
  )
  (wire (pts (xy 90.424 116.586) (xy 90.424 117.856))
    (stroke (width 0) (type default) (color 0 0 0 0))
  )
  (wire (pts (xy 84.074 129.286) (xy 90.424 129.286))
    (stroke (width 0) (type default) (color 0 0 0 0))
  )
  (wire (pts (xy 99.441 62.865) (xy 99.441 64.262))
    (stroke (width 0) (type default) (color 0 0 0 0))
  )
  (wire (pts (xy 146.05 241.3) (xy 160.655 241.3))
    (stroke (width 0) (type default) (color 0 0 0 0))
  )
  (wire (pts (xy 295.91 166.37) (xy 321.31 166.37))
    (stroke (width 0) (type default) (color 0 0 0 0))
  )
  (wire (pts (xy 90.17 228.6) (xy 90.17 229.87))
    (stroke (width 0) (type default) (color 0 0 0 0))
  )
  (wire (pts (xy 158.115 255.651) (xy 158.115 253.365))
    (stroke (width 0) (type default) (color 0 0 0 0))
  )
  (wire (pts (xy 158.115 268.605) (xy 158.115 263.525))
    (stroke (width 0) (type default) (color 0 0 0 0))
  )
  (wire (pts (xy 111.125 255.143) (xy 111.125 253.365))
    (stroke (width 0) (type default) (color 0 0 0 0))
  )
  (wire (pts (xy 316.23 153.67) (xy 308.61 153.67))
    (stroke (width 0) (type default) (color 0 0 0 0))
  )
  (wire (pts (xy 149.225 228.6) (xy 158.115 228.6))
    (stroke (width 0) (type default) (color 0 0 0 0))
  )
  (wire (pts (xy 321.31 97.79) (xy 317.5 97.79))
    (stroke (width 0) (type default) (color 0 0 0 0))
  )
  (wire (pts (xy 320.04 191.77) (xy 321.31 191.77))
    (stroke (width 0) (type default) (color 0 0 0 0))
  )
  (wire (pts (xy 295.91 95.25) (xy 321.31 95.25))
    (stroke (width 0) (type default) (color 0 0 0 0))
  )
  (wire (pts (xy 105.664 128.016) (xy 105.664 129.286))
    (stroke (width 0) (type default) (color 0 0 0 0))
  )
  (wire (pts (xy 90.424 143.256) (xy 84.074 143.256))
    (stroke (width 0) (type default) (color 0 0 0 0))
  )
  (wire (pts (xy 90.17 228.6) (xy 111.125 228.6))
    (stroke (width 0) (type default) (color 0 0 0 0))
  )
  (wire (pts (xy 125.73 266.065) (xy 111.125 266.065))
    (stroke (width 0) (type default) (color 0 0 0 0))
  )
  (wire (pts (xy 117.475 60.325) (xy 119.38 60.325))
    (stroke (width 0) (type default) (color 0 0 0 0))
  )
  (wire (pts (xy 295.91 69.85) (xy 321.31 69.85))
    (stroke (width 0) (type default) (color 0 0 0 0))
  )
  (wire (pts (xy 106.045 181.61) (xy 106.045 182.88))
    (stroke (width 0) (type default) (color 0 0 0 0))
  )
  (wire (pts (xy 146.05 236.22) (xy 149.225 236.22))
    (stroke (width 0) (type default) (color 0 0 0 0))
  )
  (wire (pts (xy 90.424 98.806) (xy 90.424 97.536))
    (stroke (width 0) (type default) (color 0 0 0 0))
  )
  (wire (pts (xy 90.424 97.536) (xy 84.074 97.536))
    (stroke (width 0) (type default) (color 0 0 0 0))
  )
  (wire (pts (xy 106.045 186.69) (xy 106.045 185.42))
    (stroke (width 0) (type default) (color 0 0 0 0))
  )
  (wire (pts (xy 90.805 205.74) (xy 90.805 204.47))
    (stroke (width 0) (type default) (color 0 0 0 0))
  )
  (wire (pts (xy 158.115 228.6) (xy 160.655 228.6))
    (stroke (width 0) (type default) (color 0 0 0 0))
  )
  (wire (pts (xy 87.757 53.34) (xy 87.757 60.325))
    (stroke (width 0) (type default) (color 0 0 0 0))
  )
  (wire (pts (xy 295.91 85.09) (xy 321.31 85.09))
    (stroke (width 0) (type default) (color 0 0 0 0))
  )
  (wire (pts (xy 149.225 260.985) (xy 146.05 260.985))
    (stroke (width 0) (type default) (color 0 0 0 0))
  )

  (text "CAM1\n" (at 71.374 92.456 0)
    (effects (font (size 1.27 1.27)) (justify left bottom))
  )
  (text "CAM0\n" (at 71.755 157.48 0)
    (effects (font (size 1.27 1.27)) (justify left bottom))
  )
  (text "3V3_CAM source selector\n& 3V3 LDO" (at 73.025 30.48 0)
    (effects (font (size 2.0066 2.0066) (thickness 0.4013) bold) (justify left bottom))
  )
  (text "Camera interfaces" (at 13.335 18.415 0)
    (effects (font (size 2.9972 2.9972) (thickness 0.5994) bold) (justify left bottom))
  )

  (label "CSI0_LN2_FFC_P" (at 295.91 123.19 0)
    (effects (font (size 1.27 1.27)) (justify left bottom))
  )
  (label "CSI0_LN3_FFC_P" (at 295.91 118.11 0)
    (effects (font (size 1.27 1.27)) (justify left bottom))
  )
  (label "CCI0_I2C_SDA_3V3" (at 179.07 266.065 180)
    (effects (font (size 1.27 1.27)) (justify right bottom))
  )
  (label "CSI0_LN0_FFC_P" (at 123.19 196.85 180)
    (effects (font (size 1.27 1.27)) (justify right bottom))
  )
  (label "CSI1_LN3_FFC_P" (at 295.91 72.39 0)
    (effects (font (size 1.27 1.27)) (justify left bottom))
  )
  (label "CSI0_CLK_FFC_P" (at 123.19 208.28 180)
    (effects (font (size 1.27 1.27)) (justify right bottom))
  )
  (label "CSI0_CLK_FFC_P" (at 295.91 140.97 0)
    (effects (font (size 1.27 1.27)) (justify left bottom))
  )
  (label "CSI1_LN0_FFC_P" (at 123.444 131.826 180)
    (effects (font (size 1.27 1.27)) (justify right bottom))
  )
  (label "CSI1_LN1_FFC_N" (at 123.444 117.856 180)
    (effects (font (size 1.27 1.27)) (justify right bottom))
  )
  (label "3V3_CAM" (at 192.405 253.365 180)
    (effects (font (size 1.27 1.27)) (justify right bottom))
  )
  (label "CSI1_LN2_FFC_P" (at 295.91 77.47 0)
    (effects (font (size 1.27 1.27)) (justify left bottom))
  )
  (label "CSI0_LN3_FFC_N" (at 295.91 115.57 0)
    (effects (font (size 1.27 1.27)) (justify left bottom))
  )
  (label "CSI1_CLK_FFC_P" (at 123.444 143.256 180)
    (effects (font (size 1.27 1.27)) (justify right bottom))
  )
  (label "CSI0_LN2_FFC_N" (at 295.91 120.65 0)
    (effects (font (size 1.27 1.27)) (justify left bottom))
  )
  (label "CSI0_LN2_FFC_P" (at 123.19 173.99 180)
    (effects (font (size 1.27 1.27)) (justify right bottom))
  )
  (label "CSI0_LN1_FFC_N" (at 123.19 182.88 180)
    (effects (font (size 1.27 1.27)) (justify right bottom))
  )
  (label "CCI0_I2C_SDA_3V3" (at 295.91 166.37 0)
    (effects (font (size 1.27 1.27)) (justify left bottom))
  )
  (label "CSI0_CLK_FFC_N" (at 123.19 205.74 180)
    (effects (font (size 1.27 1.27)) (justify right bottom))
  )
  (label "CSI0_LN0_FFC_N" (at 295.91 130.81 0)
    (effects (font (size 1.27 1.27)) (justify left bottom))
  )
  (label "CSI1_LN2_FFC_N" (at 123.444 106.426 180)
    (effects (font (size 1.27 1.27)) (justify right bottom))
  )
  (label "CSI0_LN0_FFC_N" (at 123.19 194.31 180)
    (effects (font (size 1.27 1.27)) (justify right bottom))
  )
  (label "CSI1_CLK_FFC_N" (at 123.444 140.716 180)
    (effects (font (size 1.27 1.27)) (justify right bottom))
  )
  (label "CSI1_LN0_FFC_N" (at 295.91 85.09 0)
    (effects (font (size 1.27 1.27)) (justify left bottom))
  )
  (label "CCI1_I2C_SDA_3V3" (at 179.07 241.3 180)
    (effects (font (size 1.27 1.27)) (justify right bottom))
  )
  (label "CSI0_LN3_FFC_N" (at 123.19 160.02 180)
    (effects (font (size 1.27 1.27)) (justify right bottom))
  )
  (label "CSI1_CLK_FFC_N" (at 295.91 92.71 0)
    (effects (font (size 1.27 1.27)) (justify left bottom))
  )
  (label "CSI0_LN1_FFC_P" (at 295.91 128.27 0)
    (effects (font (size 1.27 1.27)) (justify left bottom))
  )
  (label "CSI1_LN2_FFC_N" (at 295.91 74.93 0)
    (effects (font (size 1.27 1.27)) (justify left bottom))
  )
  (label "CCI0_I2C_SCL_3V3" (at 179.07 263.525 180)
    (effects (font (size 1.27 1.27)) (justify right bottom))
  )
  (label "CSI1_LN1_FFC_P" (at 123.444 120.396 180)
    (effects (font (size 1.27 1.27)) (justify right bottom))
  )
  (label "CSI1_LN1_FFC_P" (at 295.91 82.55 0)
    (effects (font (size 1.27 1.27)) (justify left bottom))
  )
  (label "3V3_CAM" (at 295.91 186.69 0)
    (effects (font (size 1.27 1.27)) (justify left bottom))
  )
  (label "CSI0_LN2_FFC_N" (at 123.19 171.45 180)
    (effects (font (size 1.27 1.27)) (justify right bottom))
  )
  (label "CSI0_LN0_FFC_P" (at 295.91 133.35 0)
    (effects (font (size 1.27 1.27)) (justify left bottom))
  )
  (label "CSI1_LN3_FFC_N" (at 295.91 69.85 0)
    (effects (font (size 1.27 1.27)) (justify left bottom))
  )
  (label "CCI0_I2C_SCL_3V3" (at 295.91 168.91 0)
    (effects (font (size 1.27 1.27)) (justify left bottom))
  )
  (label "CCI1_I2C_SCL_3V3" (at 179.07 238.76 180)
    (effects (font (size 1.27 1.27)) (justify right bottom))
  )
  (label "3V3_CAM" (at 191.77 228.6 180)
    (effects (font (size 1.27 1.27)) (justify right bottom))
  )
  (label "CSI1_LN0_FFC_N" (at 123.444 129.286 180)
    (effects (font (size 1.27 1.27)) (justify right bottom))
  )
  (label "CCI1_I2C_SCL_3V3" (at 295.91 173.99 0)
    (effects (font (size 1.27 1.27)) (justify left bottom))
  )
  (label "3V3_CAM" (at 154.305 46.99 180)
    (effects (font (size 1.27 1.27)) (justify right bottom))
  )
  (label "CSI1_LN3_FFC_P" (at 123.444 97.536 180)
    (effects (font (size 1.27 1.27)) (justify right bottom))
  )
  (label "CSI1_LN1_FFC_N" (at 295.91 80.01 0)
    (effects (font (size 1.27 1.27)) (justify left bottom))
  )
  (label "CSI0_CLK_FFC_N" (at 295.91 138.43 0)
    (effects (font (size 1.27 1.27)) (justify left bottom))
  )
  (label "CSI1_LN2_FFC_P" (at 123.444 108.966 180)
    (effects (font (size 1.27 1.27)) (justify right bottom))
  )
  (label "CSI1_LN0_FFC_P" (at 295.91 87.63 0)
    (effects (font (size 1.27 1.27)) (justify left bottom))
  )
  (label "CSI0_LN3_FFC_P" (at 123.19 162.56 180)
    (effects (font (size 1.27 1.27)) (justify right bottom))
  )
  (label "CSI1_CLK_FFC_P" (at 295.91 95.25 0)
    (effects (font (size 1.27 1.27)) (justify left bottom))
  )
  (label "CSI1_LN3_FFC_N" (at 123.444 94.996 180)
    (effects (font (size 1.27 1.27)) (justify right bottom))
  )
  (label "CSI0_LN1_FFC_N" (at 295.91 125.73 0)
    (effects (font (size 1.27 1.27)) (justify left bottom))
  )
  (label "CCI1_I2C_SDA_3V3" (at 295.91 171.45 0)
    (effects (font (size 1.27 1.27)) (justify left bottom))
  )
  (label "CSI0_LN1_FFC_P" (at 123.19 185.42 180)
    (effects (font (size 1.27 1.27)) (justify right bottom))
  )

  (global_label "CSI0_LN1_P" (shape input) (at 84.455 185.42 180) (fields_autoplaced)
    (effects (font (size 1.27 1.27)) (justify right))
    (property "Intersheet References" "${INTERSHEET_REFS}" (id 0) (at 71.0637 185.3406 0)
      (effects (font (size 1.27 1.27)) (justify right) hide)
    )
  )
  (global_label "CSI0_LN2_P" (shape input) (at 84.455 173.99 180) (fields_autoplaced)
    (effects (font (size 1.27 1.27)) (justify right))
    (property "Intersheet References" "${INTERSHEET_REFS}" (id 0) (at 71.0637 173.9106 0)
      (effects (font (size 1.27 1.27)) (justify right) hide)
    )
  )
  (global_label "CAM0_RST" (shape input) (at 306.705 151.13 180) (fields_autoplaced)
    (effects (font (size 1.27 1.27)) (justify right))
    (property "Intersheet References" "${INTERSHEET_REFS}" (id 0) (at 0 0 0)
      (effects (font (size 1.27 1.27)) hide)
    )
  )
  (global_label "CSI1_CLK_P" (shape input) (at 84.074 143.256 180) (fields_autoplaced)
    (effects (font (size 1.27 1.27)) (justify right))
    (property "Intersheet References" "${INTERSHEET_REFS}" (id 0) (at 70.6827 143.1766 0)
      (effects (font (size 1.27 1.27)) (justify right) hide)
    )
  )
  (global_label "CCI1_I2C_SDA" (shape input) (at 107.315 241.3 180) (fields_autoplaced)
    (effects (font (size 1.27 1.27)) (justify right))
    (property "Intersheet References" "${INTERSHEET_REFS}" (id 0) (at 92.0489 241.2206 0)
      (effects (font (size 1.27 1.27)) (justify right) hide)
    )
  )
  (global_label "5V_SYS" (shape input) (at 304.165 191.77 180) (fields_autoplaced)
    (effects (font (size 1.27 1.27)) (justify right))
    (property "Intersheet References" "${INTERSHEET_REFS}" (id 0) (at 0 0 0)
      (effects (font (size 1.27 1.27)) hide)
    )
  )
  (global_label "CSI0_LN3_N" (shape input) (at 84.455 160.02 180) (fields_autoplaced)
    (effects (font (size 1.27 1.27)) (justify right))
    (property "Intersheet References" "${INTERSHEET_REFS}" (id 0) (at 71.0032 159.9406 0)
      (effects (font (size 1.27 1.27)) (justify right) hide)
    )
  )
  (global_label "CCI0_I2C_SCL" (shape input) (at 107.315 263.525 180) (fields_autoplaced)
    (effects (font (size 1.27 1.27)) (justify right))
    (property "Intersheet References" "${INTERSHEET_REFS}" (id 0) (at 92.1094 263.4456 0)
      (effects (font (size 1.27 1.27)) (justify right) hide)
    )
  )
  (global_label "3V3_SYS" (shape input) (at 91.44 34.29 180) (fields_autoplaced)
    (effects (font (size 1.27 1.27)) (justify right))
    (property "Intersheet References" "${INTERSHEET_REFS}" (id 0) (at 81.1329 34.2106 0)
      (effects (font (size 1.27 1.27)) (justify right) hide)
    )
  )
  (global_label "CSI1_LN0_P" (shape input) (at 84.074 131.826 180) (fields_autoplaced)
    (effects (font (size 1.27 1.27)) (justify right))
    (property "Intersheet References" "${INTERSHEET_REFS}" (id 0) (at 70.6827 131.7466 0)
      (effects (font (size 1.27 1.27)) (justify right) hide)
    )
  )
  (global_label "CSI1_LN2_N" (shape input) (at 84.074 106.426 180) (fields_autoplaced)
    (effects (font (size 1.27 1.27)) (justify right))
    (property "Intersheet References" "${INTERSHEET_REFS}" (id 0) (at 70.6222 106.3466 0)
      (effects (font (size 1.27 1.27)) (justify right) hide)
    )
  )
  (global_label "CSI1_LN2_P" (shape input) (at 84.074 108.966 180) (fields_autoplaced)
    (effects (font (size 1.27 1.27)) (justify right))
    (property "Intersheet References" "${INTERSHEET_REFS}" (id 0) (at 70.6827 108.8866 0)
      (effects (font (size 1.27 1.27)) (justify right) hide)
    )
  )
  (global_label "CSI0_CLK_N" (shape input) (at 84.455 205.74 180) (fields_autoplaced)
    (effects (font (size 1.27 1.27)) (justify right))
    (property "Intersheet References" "${INTERSHEET_REFS}" (id 0) (at 71.0032 205.6606 0)
      (effects (font (size 1.27 1.27)) (justify right) hide)
    )
  )
  (global_label "CSI1_LN0_N" (shape input) (at 84.074 129.286 180) (fields_autoplaced)
    (effects (font (size 1.27 1.27)) (justify right))
    (property "Intersheet References" "${INTERSHEET_REFS}" (id 0) (at 70.6222 129.2066 0)
      (effects (font (size 1.27 1.27)) (justify right) hide)
    )
  )
  (global_label "CSI0_CLK_P" (shape input) (at 84.455 208.28 180) (fields_autoplaced)
    (effects (font (size 1.27 1.27)) (justify right))
    (property "Intersheet References" "${INTERSHEET_REFS}" (id 0) (at 71.0637 208.2006 0)
      (effects (font (size 1.27 1.27)) (justify right) hide)
    )
  )
  (global_label "CSI0_LN3_P" (shape input) (at 84.455 162.56 180) (fields_autoplaced)
    (effects (font (size 1.27 1.27)) (justify right))
    (property "Intersheet References" "${INTERSHEET_REFS}" (id 0) (at 71.0637 162.4806 0)
      (effects (font (size 1.27 1.27)) (justify right) hide)
    )
  )
  (global_label "CSI0_LN0_N" (shape input) (at 84.455 194.31 180) (fields_autoplaced)
    (effects (font (size 1.27 1.27)) (justify right))
    (property "Intersheet References" "${INTERSHEET_REFS}" (id 0) (at 71.0032 194.2306 0)
      (effects (font (size 1.27 1.27)) (justify right) hide)
    )
  )
  (global_label "LVS1A_1V8" (shape input) (at 83.82 253.365 180) (fields_autoplaced)
    (effects (font (size 1.27 1.27)) (justify right))
    (property "Intersheet References" "${INTERSHEET_REFS}" (id 0) (at 71.3963 253.2856 0)
      (effects (font (size 1.27 1.27)) (justify right) hide)
    )
  )
  (global_label "CCI1_I2C_SCL" (shape input) (at 107.315 238.76 180) (fields_autoplaced)
    (effects (font (size 1.27 1.27)) (justify right))
    (property "Intersheet References" "${INTERSHEET_REFS}" (id 0) (at 92.1094 238.6806 0)
      (effects (font (size 1.27 1.27)) (justify right) hide)
    )
  )
  (global_label "CSI1_LN1_P" (shape input) (at 84.074 120.396 180) (fields_autoplaced)
    (effects (font (size 1.27 1.27)) (justify right))
    (property "Intersheet References" "${INTERSHEET_REFS}" (id 0) (at 70.6827 120.3166 0)
      (effects (font (size 1.27 1.27)) (justify right) hide)
    )
  )
  (global_label "CAM1_PWDN" (shape input) (at 308.61 153.67 180) (fields_autoplaced)
    (effects (font (size 1.27 1.27)) (justify right))
    (property "Intersheet References" "${INTERSHEET_REFS}" (id 0) (at 0 0 0)
      (effects (font (size 1.27 1.27)) hide)
    )
  )
  (global_label "CAM0_PWDN" (shape input) (at 308.61 148.59 180) (fields_autoplaced)
    (effects (font (size 1.27 1.27)) (justify right))
    (property "Intersheet References" "${INTERSHEET_REFS}" (id 0) (at 0 0 0)
      (effects (font (size 1.27 1.27)) hide)
    )
  )
  (global_label "CCI0_I2C_SDA" (shape input) (at 107.315 266.065 180) (fields_autoplaced)
    (effects (font (size 1.27 1.27)) (justify right))
    (property "Intersheet References" "${INTERSHEET_REFS}" (id 0) (at 92.0489 265.9856 0)
      (effects (font (size 1.27 1.27)) (justify right) hide)
    )
  )
  (global_label "CSI0_LN2_N" (shape input) (at 84.455 171.45 180) (fields_autoplaced)
    (effects (font (size 1.27 1.27)) (justify right))
    (property "Intersheet References" "${INTERSHEET_REFS}" (id 0) (at 71.0032 171.3706 0)
      (effects (font (size 1.27 1.27)) (justify right) hide)
    )
  )
  (global_label "CSI0_LN0_P" (shape input) (at 84.455 196.85 180) (fields_autoplaced)
    (effects (font (size 1.27 1.27)) (justify right))
    (property "Intersheet References" "${INTERSHEET_REFS}" (id 0) (at 71.0637 196.7706 0)
      (effects (font (size 1.27 1.27)) (justify right) hide)
    )
  )
  (global_label "CSI0_LN1_N" (shape input) (at 84.455 182.88 180) (fields_autoplaced)
    (effects (font (size 1.27 1.27)) (justify right))
    (property "Intersheet References" "${INTERSHEET_REFS}" (id 0) (at 71.0032 182.8006 0)
      (effects (font (size 1.27 1.27)) (justify right) hide)
    )
  )
  (global_label "CSI1_LN3_N" (shape input) (at 84.074 94.996 180) (fields_autoplaced)
    (effects (font (size 1.27 1.27)) (justify right))
    (property "Intersheet References" "${INTERSHEET_REFS}" (id 0) (at 70.6222 94.9166 0)
      (effects (font (size 1.27 1.27)) (justify right) hide)
    )
  )
  (global_label "CSI1_CLK_N" (shape input) (at 84.074 140.716 180) (fields_autoplaced)
    (effects (font (size 1.27 1.27)) (justify right))
    (property "Intersheet References" "${INTERSHEET_REFS}" (id 0) (at 70.6222 140.6366 0)
      (effects (font (size 1.27 1.27)) (justify right) hide)
    )
  )
  (global_label "5V_SYS" (shape input) (at 86.487 60.325 180) (fields_autoplaced)
    (effects (font (size 1.27 1.27)) (justify right))
    (property "Intersheet References" "${INTERSHEET_REFS}" (id 0) (at 77.3895 60.2456 0)
      (effects (font (size 1.27 1.27)) (justify right) hide)
    )
  )
  (global_label "CSI1_LN1_N" (shape input) (at 84.074 117.856 180) (fields_autoplaced)
    (effects (font (size 1.27 1.27)) (justify right))
    (property "Intersheet References" "${INTERSHEET_REFS}" (id 0) (at 70.6222 117.7766 0)
      (effects (font (size 1.27 1.27)) (justify right) hide)
    )
  )
  (global_label "LVS1A_1V8" (shape input) (at 83.82 228.6 180) (fields_autoplaced)
    (effects (font (size 1.27 1.27)) (justify right))
    (property "Intersheet References" "${INTERSHEET_REFS}" (id 0) (at 71.3963 228.5206 0)
      (effects (font (size 1.27 1.27)) (justify right) hide)
    )
  )
  (global_label "CSI1_LN3_P" (shape input) (at 84.074 97.536 180) (fields_autoplaced)
    (effects (font (size 1.27 1.27)) (justify right))
    (property "Intersheet References" "${INTERSHEET_REFS}" (id 0) (at 70.6827 97.4566 0)
      (effects (font (size 1.27 1.27)) (justify right) hide)
    )
  )

  (symbol (lib_id "sa800u-baseboard-hw:Conn_FFC_WE_68715014522_TWO-SIDES") (at 321.31 69.85 0) (unit 1)
    (in_bom yes) (on_board yes) (fields_autoplaced)
    (property "Reference" "J7" (id 0) (at 330.2 133.9849 0)
      (effects (font (size 1.27 1.27)) (justify left))
    )
    (property "Value" "Conn_FFC_WE_68715014522_TWO-SIDES" (id 1) (at 323.342 92.6846 0)
      (effects (font (size 1.27 1.27)) (justify left) hide)
    )
    (property "Footprint" "sa800u-baseboard-hw-footprints:Conn_FFC_WE_68715014x22_ALT" (id 2) (at 316.23 160.02 0)
      (effects (font (size 1.27 1.27)) hide)
    )
    (property "Datasheet" "https://www.we-online.com/components/products/datasheet/68715014522.pdf" (id 3) (at 321.31 162.56 0)
      (effects (font (size 1.27 1.27)) hide)
    )
    (property "MPN" "68715014522" (id 4) (at 330.2 137.16 0)
      (effects (font (size 1.524 1.524)) (justify left))
    )
    (property "Manufacturer" "Würth Elektronik" (id 5) (at 337.82 115.57 0)
      (effects (font (size 1.524 1.524)) (justify left) hide)
    )
    (property "Author" "Antmicro" (id 6) (at 340.36 90.17 0)
      (effects (font (size 1.27 1.27) (thickness 0.15)) (justify left bottom) hide)
    )
    (property "License" "Apache-2.0" (id 7) (at 340.36 92.71 0)
      (effects (font (size 1.27 1.27) (thickness 0.15)) (justify left bottom) hide)
    )
    (pin "1")
    (pin "10")
    (pin "11")
    (pin "12")
    (pin "13")
    (pin "14")
    (pin "15")
    (pin "16")
    (pin "17")
    (pin "18")
    (pin "19")
    (pin "2")
    (pin "20")
    (pin "21")
    (pin "22")
    (pin "23")
    (pin "24")
    (pin "25")
    (pin "26")
    (pin "27")
    (pin "28")
    (pin "29")
    (pin "3")
    (pin "30")
    (pin "31")
    (pin "32")
    (pin "33")
    (pin "34")
    (pin "35")
    (pin "36")
    (pin "37")
    (pin "38")
    (pin "39")
    (pin "4")
    (pin "40")
    (pin "41")
    (pin "42")
    (pin "43")
    (pin "44")
    (pin "45")
    (pin "46")
    (pin "47")
    (pin "48")
    (pin "49")
    (pin "5")
    (pin "50")
    (pin "6")
    (pin "7")
    (pin "8")
    (pin "9")
    (pin "SH1")
    (pin "SH2")
  )

  (symbol (lib_id "sa800u-baseboard-hw:GND") (at 317.5 204.47 0) (unit 1)
    (in_bom yes) (on_board yes)
    (property "Reference" "#PWR0181" (id 0) (at 317.5 210.82 0)
      (effects (font (size 1.27 1.27)) hide)
    )
    (property "Value" "GND" (id 1) (at 317.627 208.8642 0))
    (property "Footprint" "" (id 2) (at 317.5 204.47 0)
      (effects (font (size 1.27 1.27)) hide)
    )
    (property "Datasheet" "" (id 3) (at 317.5 204.47 0)
      (effects (font (size 1.27 1.27)) hide)
    )
    (property "Author" "Antmicro" (id 4) (at 326.39 212.09 0)
      (effects (font (size 1.27 1.27) (thickness 0.15)) (justify left bottom) hide)
    )
    (property "License" "Apache-2.0" (id 5) (at 326.39 214.63 0)
      (effects (font (size 1.27 1.27) (thickness 0.15)) (justify left bottom) hide)
    )
    (pin "1")
  )

  (symbol (lib_name "NFP0QHB242HS2D_7") (lib_id "sa800u-baseboard-hw:NFP0QHB242HS2D") (at 90.424 98.806 0) (mirror x) (unit 1)
    (in_bom yes) (on_board yes) (fields_autoplaced)
    (property "Reference" "L16" (id 0) (at 97.6249 88.9 0))
    (property "Value" "NFP0QHB242HS2D" (id 1) (at 97.6249 91.44 0))
    (property "Footprint" "sa800u-baseboard-hw-footprints:L_Murata_025020_0605Metric" (id 2) (at 84.201 107.188 0)
      (effects (font (size 1.27 1.27)) hide)
    )
    (property "Datasheet" "https://www.farnell.com/datasheets/2616945.pdf" (id 3) (at 90.424 98.806 0)
      (effects (font (size 1.27 1.27)) hide)
    )
    (property "MPN" "NFP0QHB242HS2D" (id 4) (at 90.424 106.8578 0)
      (effects (font (size 1.27 1.27)) hide)
    )
    (property "Manufacturer" "Murata" (id 5) (at 90.424 104.5464 0)
      (effects (font (size 1.27 1.27)) hide)
    )
    (property "Author" "Antmicro" (id 6) (at 122.174 78.486 0)
      (effects (font (size 1.27 1.27) (thickness 0.15)) (justify left bottom) hide)
    )
    (property "License" "Apache-2.0" (id 7) (at 122.174 75.946 0)
      (effects (font (size 1.27 1.27) (thickness 0.15)) (justify left bottom) hide)
    )
    (pin "1")
    (pin "2")
    (pin "3")
    (pin "4")
  )

  (symbol (lib_name "NFP0QHB242HS2D_6") (lib_id "sa800u-baseboard-hw:NFP0QHB242HS2D") (at 90.424 110.236 0) (mirror x) (unit 1)
    (in_bom yes) (on_board yes) (fields_autoplaced)
    (property "Reference" "L17" (id 0) (at 97.6249 100.33 0))
    (property "Value" "NFP0QHB242HS2D" (id 1) (at 97.6249 102.87 0))
    (property "Footprint" "sa800u-baseboard-hw-footprints:L_Murata_025020_0605Metric" (id 2) (at 84.201 118.618 0)
      (effects (font (size 1.27 1.27)) hide)
    )
    (property "Datasheet" "https://www.farnell.com/datasheets/2616945.pdf" (id 3) (at 90.424 110.236 0)
      (effects (font (size 1.27 1.27)) hide)
    )
    (property "MPN" "NFP0QHB242HS2D" (id 4) (at 90.424 118.2878 0)
      (effects (font (size 1.27 1.27)) hide)
    )
    (property "Manufacturer" "Murata" (id 5) (at 90.424 115.9764 0)
      (effects (font (size 1.27 1.27)) hide)
    )
    (property "Author" "Antmicro" (id 6) (at 122.174 89.916 0)
      (effects (font (size 1.27 1.27) (thickness 0.15)) (justify left bottom) hide)
    )
    (property "License" "Apache-2.0" (id 7) (at 122.174 87.376 0)
      (effects (font (size 1.27 1.27) (thickness 0.15)) (justify left bottom) hide)
    )
    (pin "1")
    (pin "2")
    (pin "3")
    (pin "4")
  )

  (symbol (lib_id "sa800u-baseboard-hw:NFP0QHB242HS2D") (at 90.424 121.666 0) (mirror x) (unit 1)
    (in_bom yes) (on_board yes) (fields_autoplaced)
    (property "Reference" "L18" (id 0) (at 97.6249 111.76 0))
    (property "Value" "NFP0QHB242HS2D" (id 1) (at 97.6249 114.3 0))
    (property "Footprint" "sa800u-baseboard-hw-footprints:L_Murata_025020_0605Metric" (id 2) (at 84.201 130.048 0)
      (effects (font (size 1.27 1.27)) hide)
    )
    (property "Datasheet" "https://www.farnell.com/datasheets/2616945.pdf" (id 3) (at 90.424 121.666 0)
      (effects (font (size 1.27 1.27)) hide)
    )
    (property "MPN" "NFP0QHB242HS2D" (id 4) (at 90.424 129.7178 0)
      (effects (font (size 1.27 1.27)) hide)
    )
    (property "Manufacturer" "Murata" (id 5) (at 90.424 127.4064 0)
      (effects (font (size 1.27 1.27)) hide)
    )
    (property "Author" "Antmicro" (id 6) (at 122.174 101.346 0)
      (effects (font (size 1.27 1.27) (thickness 0.15)) (justify left bottom) hide)
    )
    (property "License" "Apache-2.0" (id 7) (at 122.174 98.806 0)
      (effects (font (size 1.27 1.27) (thickness 0.15)) (justify left bottom) hide)
    )
    (pin "1")
    (pin "2")
    (pin "3")
    (pin "4")
  )

  (symbol (lib_name "NFP0QHB242HS2D_9") (lib_id "sa800u-baseboard-hw:NFP0QHB242HS2D") (at 90.424 133.096 0) (mirror x) (unit 1)
    (in_bom yes) (on_board yes) (fields_autoplaced)
    (property "Reference" "L19" (id 0) (at 97.6249 123.19 0))
    (property "Value" "NFP0QHB242HS2D" (id 1) (at 97.6249 125.73 0))
    (property "Footprint" "sa800u-baseboard-hw-footprints:L_Murata_025020_0605Metric" (id 2) (at 84.201 141.478 0)
      (effects (font (size 1.27 1.27)) hide)
    )
    (property "Datasheet" "https://www.farnell.com/datasheets/2616945.pdf" (id 3) (at 90.424 133.096 0)
      (effects (font (size 1.27 1.27)) hide)
    )
    (property "MPN" "NFP0QHB242HS2D" (id 4) (at 90.424 141.1478 0)
      (effects (font (size 1.27 1.27)) hide)
    )
    (property "Manufacturer" "Murata" (id 5) (at 90.424 138.8364 0)
      (effects (font (size 1.27 1.27)) hide)
    )
    (property "Author" "Antmicro" (id 6) (at 122.174 112.776 0)
      (effects (font (size 1.27 1.27) (thickness 0.15)) (justify left bottom) hide)
    )
    (property "License" "Apache-2.0" (id 7) (at 122.174 110.236 0)
      (effects (font (size 1.27 1.27) (thickness 0.15)) (justify left bottom) hide)
    )
    (pin "1")
    (pin "2")
    (pin "3")
    (pin "4")
  )

  (symbol (lib_name "NFP0QHB242HS2D_8") (lib_id "sa800u-baseboard-hw:NFP0QHB242HS2D") (at 90.424 144.526 0) (mirror x) (unit 1)
    (in_bom yes) (on_board yes) (fields_autoplaced)
    (property "Reference" "L20" (id 0) (at 97.6249 134.62 0))
    (property "Value" "NFP0QHB242HS2D" (id 1) (at 97.6249 137.16 0))
    (property "Footprint" "sa800u-baseboard-hw-footprints:L_Murata_025020_0605Metric" (id 2) (at 84.201 152.908 0)
      (effects (font (size 1.27 1.27)) hide)
    )
    (property "Datasheet" "https://www.farnell.com/datasheets/2616945.pdf" (id 3) (at 90.424 144.526 0)
      (effects (font (size 1.27 1.27)) hide)
    )
    (property "MPN" "NFP0QHB242HS2D" (id 4) (at 90.424 152.5778 0)
      (effects (font (size 1.27 1.27)) hide)
    )
    (property "Manufacturer" "Murata" (id 5) (at 90.424 150.2664 0)
      (effects (font (size 1.27 1.27)) hide)
    )
    (property "Author" "Antmicro" (id 6) (at 122.174 124.206 0)
      (effects (font (size 1.27 1.27) (thickness 0.15)) (justify left bottom) hide)
    )
    (property "License" "Apache-2.0" (id 7) (at 122.174 121.666 0)
      (effects (font (size 1.27 1.27) (thickness 0.15)) (justify left bottom) hide)
    )
    (pin "1")
    (pin "2")
    (pin "3")
    (pin "4")
  )

  (symbol (lib_name "NFP0QHB242HS2D_3") (lib_id "sa800u-baseboard-hw:NFP0QHB242HS2D") (at 90.805 163.83 0) (mirror x) (unit 1)
    (in_bom yes) (on_board yes) (fields_autoplaced)
    (property "Reference" "L21" (id 0) (at 98.0059 153.67 0))
    (property "Value" "NFP0QHB242HS2D" (id 1) (at 98.0059 156.21 0))
    (property "Footprint" "sa800u-baseboard-hw-footprints:L_Murata_025020_0605Metric" (id 2) (at 84.582 172.212 0)
      (effects (font (size 1.27 1.27)) hide)
    )
    (property "Datasheet" "https://www.farnell.com/datasheets/2616945.pdf" (id 3) (at 90.805 163.83 0)
      (effects (font (size 1.27 1.27)) hide)
    )
    (property "MPN" "NFP0QHB242HS2D" (id 4) (at 90.805 171.8818 0)
      (effects (font (size 1.27 1.27)) hide)
    )
    (property "Manufacturer" "Murata" (id 5) (at 90.805 169.5704 0)
      (effects (font (size 1.27 1.27)) hide)
    )
    (property "Author" "Antmicro" (id 6) (at 122.555 143.51 0)
      (effects (font (size 1.27 1.27) (thickness 0.15)) (justify left bottom) hide)
    )
    (property "License" "Apache-2.0" (id 7) (at 122.555 140.97 0)
      (effects (font (size 1.27 1.27) (thickness 0.15)) (justify left bottom) hide)
    )
    (pin "1")
    (pin "2")
    (pin "3")
    (pin "4")
  )

  (symbol (lib_name "NFP0QHB242HS2D_5") (lib_id "sa800u-baseboard-hw:NFP0QHB242HS2D") (at 90.805 175.26 0) (mirror x) (unit 1)
    (in_bom yes) (on_board yes) (fields_autoplaced)
    (property "Reference" "L22" (id 0) (at 98.0059 165.1 0))
    (property "Value" "NFP0QHB242HS2D" (id 1) (at 98.0059 167.64 0))
    (property "Footprint" "sa800u-baseboard-hw-footprints:L_Murata_025020_0605Metric" (id 2) (at 84.582 183.642 0)
      (effects (font (size 1.27 1.27)) hide)
    )
    (property "Datasheet" "https://www.farnell.com/datasheets/2616945.pdf" (id 3) (at 90.805 175.26 0)
      (effects (font (size 1.27 1.27)) hide)
    )
    (property "MPN" "NFP0QHB242HS2D" (id 4) (at 90.805 183.3118 0)
      (effects (font (size 1.27 1.27)) hide)
    )
    (property "Manufacturer" "Murata" (id 5) (at 90.805 181.0004 0)
      (effects (font (size 1.27 1.27)) hide)
    )
    (property "Author" "Antmicro" (id 6) (at 122.555 154.94 0)
      (effects (font (size 1.27 1.27) (thickness 0.15)) (justify left bottom) hide)
    )
    (property "License" "Apache-2.0" (id 7) (at 122.555 152.4 0)
      (effects (font (size 1.27 1.27) (thickness 0.15)) (justify left bottom) hide)
    )
    (pin "1")
    (pin "2")
    (pin "3")
    (pin "4")
  )

  (symbol (lib_name "NFP0QHB242HS2D_4") (lib_id "sa800u-baseboard-hw:NFP0QHB242HS2D") (at 90.805 186.69 0) (mirror x) (unit 1)
    (in_bom yes) (on_board yes) (fields_autoplaced)
    (property "Reference" "L23" (id 0) (at 98.0059 176.53 0))
    (property "Value" "NFP0QHB242HS2D" (id 1) (at 98.0059 179.07 0))
    (property "Footprint" "sa800u-baseboard-hw-footprints:L_Murata_025020_0605Metric" (id 2) (at 84.582 195.072 0)
      (effects (font (size 1.27 1.27)) hide)
    )
    (property "Datasheet" "https://www.farnell.com/datasheets/2616945.pdf" (id 3) (at 90.805 186.69 0)
      (effects (font (size 1.27 1.27)) hide)
    )
    (property "MPN" "NFP0QHB242HS2D" (id 4) (at 90.805 194.7418 0)
      (effects (font (size 1.27 1.27)) hide)
    )
    (property "Manufacturer" "Murata" (id 5) (at 90.805 192.4304 0)
      (effects (font (size 1.27 1.27)) hide)
    )
    (property "Author" "Antmicro" (id 6) (at 122.555 166.37 0)
      (effects (font (size 1.27 1.27) (thickness 0.15)) (justify left bottom) hide)
    )
    (property "License" "Apache-2.0" (id 7) (at 122.555 163.83 0)
      (effects (font (size 1.27 1.27) (thickness 0.15)) (justify left bottom) hide)
    )
    (pin "1")
    (pin "2")
    (pin "3")
    (pin "4")
  )

  (symbol (lib_name "NFP0QHB242HS2D_1") (lib_id "sa800u-baseboard-hw:NFP0QHB242HS2D") (at 90.805 198.12 0) (mirror x) (unit 1)
    (in_bom yes) (on_board yes) (fields_autoplaced)
    (property "Reference" "L24" (id 0) (at 98.0059 187.96 0))
    (property "Value" "NFP0QHB242HS2D" (id 1) (at 98.0059 190.5 0))
    (property "Footprint" "sa800u-baseboard-hw-footprints:L_Murata_025020_0605Metric" (id 2) (at 84.582 206.502 0)
      (effects (font (size 1.27 1.27)) hide)
    )
    (property "Datasheet" "https://www.farnell.com/datasheets/2616945.pdf" (id 3) (at 90.805 198.12 0)
      (effects (font (size 1.27 1.27)) hide)
    )
    (property "MPN" "NFP0QHB242HS2D" (id 4) (at 90.805 206.1718 0)
      (effects (font (size 1.27 1.27)) hide)
    )
    (property "Manufacturer" "Murata" (id 5) (at 90.805 203.8604 0)
      (effects (font (size 1.27 1.27)) hide)
    )
    (property "Author" "Antmicro" (id 6) (at 122.555 177.8 0)
      (effects (font (size 1.27 1.27) (thickness 0.15)) (justify left bottom) hide)
    )
    (property "License" "Apache-2.0" (id 7) (at 122.555 175.26 0)
      (effects (font (size 1.27 1.27) (thickness 0.15)) (justify left bottom) hide)
    )
    (pin "1")
    (pin "2")
    (pin "3")
    (pin "4")
  )

  (symbol (lib_name "NFP0QHB242HS2D_2") (lib_id "sa800u-baseboard-hw:NFP0QHB242HS2D") (at 90.805 209.55 0) (mirror x) (unit 1)
    (in_bom yes) (on_board yes) (fields_autoplaced)
    (property "Reference" "L25" (id 0) (at 98.0059 199.39 0))
    (property "Value" "NFP0QHB242HS2D" (id 1) (at 98.0059 201.93 0))
    (property "Footprint" "sa800u-baseboard-hw-footprints:L_Murata_025020_0605Metric" (id 2) (at 84.582 217.932 0)
      (effects (font (size 1.27 1.27)) hide)
    )
    (property "Datasheet" "https://www.farnell.com/datasheets/2616945.pdf" (id 3) (at 90.805 209.55 0)
      (effects (font (size 1.27 1.27)) hide)
    )
    (property "MPN" "NFP0QHB242HS2D" (id 4) (at 90.805 217.6018 0)
      (effects (font (size 1.27 1.27)) hide)
    )
    (property "Manufacturer" "Murata" (id 5) (at 90.805 215.2904 0)
      (effects (font (size 1.27 1.27)) hide)
    )
    (property "Author" "Antmicro" (id 6) (at 122.555 189.23 0)
      (effects (font (size 1.27 1.27) (thickness 0.15)) (justify left bottom) hide)
    )
    (property "License" "Apache-2.0" (id 7) (at 122.555 186.69 0)
      (effects (font (size 1.27 1.27) (thickness 0.15)) (justify left bottom) hide)
    )
    (pin "1")
    (pin "2")
    (pin "3")
    (pin "4")
  )

  (symbol (lib_id "sa800u-baseboard-hw:AP2114H-3.3TRG1") (at 100.965 60.325 0) (unit 1)
    (in_bom yes) (on_board yes) (fields_autoplaced)
    (property "Reference" "U12" (id 0) (at 109.22 49.403 0)
      (effects (font (size 1.524 1.524)))
    )
    (property "Value" "AP2114H-3.3TRG1" (id 1) (at 133.985 67.945 0)
      (effects (font (size 1.27 1.27) (thickness 0.15)) (justify left bottom) hide)
    )
    (property "Footprint" "sa800u-baseboard-hw-footprints:SOT-223" (id 2) (at 133.985 70.485 0)
      (effects (font (size 1.27 1.27) (thickness 0.15)) (justify left bottom) hide)
    )
    (property "Datasheet" "https://www.diodes.com/assets/Datasheets/AP2114.pdf" (id 3) (at 133.985 73.025 0)
      (effects (font (size 1.27 1.27) (thickness 0.15)) (justify left bottom) hide)
    )
    (property "MPN" "AP2114H-3.3TRG1" (id 4) (at 109.22 51.943 0)
      (effects (font (size 1.27 1.27) (thickness 0.15)))
    )
    (property "Manufacturer" "Diodes Incorporated" (id 5) (at 133.985 75.565 0)
      (effects (font (size 1.27 1.27) (thickness 0.15)) (justify left bottom) hide)
    )
    (property "DNP" "DNP" (id 6) (at 109.22 54.483 0))
    (property "Author" "Antmicro" (id 7) (at 133.985 78.105 0)
      (effects (font (size 1.27 1.27) (thickness 0.15)) (justify left bottom) hide)
    )
    (property "License" "Apache-2.0" (id 8) (at 133.985 80.645 0)
      (effects (font (size 1.27 1.27) (thickness 0.15)) (justify left bottom) hide)
    )
    (pin "1")
    (pin "2")
    (pin "3")
    (pin "4")
  )

  (symbol (lib_id "sa800u-baseboard-hw:C_4u7_0805") (at 119.38 61.595 270) (unit 1)
    (in_bom yes) (on_board yes) (fields_autoplaced)
    (property "Reference" "C108" (id 0) (at 122.809 61.6013 90)
      (effects (font (size 1.524 1.524)) (justify left))
    )
    (property "Value" "C_4u7_0805" (id 1) (at 115.57 61.595 0)
      (effects (font (size 1.524 1.524)) hide)
    )
    (property "Footprint" "sa800u-baseboard-hw-footprints:C_0805_2012Metric" (id 2) (at 124.46 66.675 0)
      (effects (font (size 1.524 1.524)) (justify left) hide)
    )
    (property "Datasheet" " " (id 3) (at 119.38 61.595 0)
      (effects (font (size 1.27 1.27)) hide)
    )
    (property "Manufacturer" "Walsin" (id 4) (at 129.54 66.675 0)
      (effects (font (size 1.524 1.524)) (justify left) hide)
    )
    (property "MPN" "0805X475K250CT" (id 5) (at 127 66.675 0)
      (effects (font (size 1.524 1.524)) (justify left) hide)
    )
    (property "Val" "4u7" (id 6) (at 122.809 64.7762 90)
      (effects (font (size 1.27 1.27)) (justify left))
    )
    (property "DNP" "DNP" (id 7) (at 122.809 67.3162 90)
      (effects (font (size 1.27 1.27)) (justify left))
    )
    (property "License" "Apache-2.0" (id 8) (at 96.52 81.915 0)
      (effects (font (size 1.27 1.27) (thickness 0.15)) (justify left bottom) hide)
    )
    (property "Author" "Antmicro" (id 9) (at 93.98 81.915 0)
      (effects (font (size 1.27 1.27) (thickness 0.15)) (justify left bottom) hide)
    )
    (property "Voltage" "" (id 10) (at 91.44 81.915 0)
      (effects (font (size 1.27 1.27)) (justify left bottom) hide)
    )
    (property "Dielectric" "" (id 11) (at 88.9 81.915 0)
      (effects (font (size 1.27 1.27)) (justify left bottom) hide)
    )
    (pin "1")
    (pin "2")
  )

  (symbol (lib_id "sa800u-baseboard-hw:C_4u7_0805") (at 87.757 64.135 270) (unit 1)
    (in_bom yes) (on_board yes) (fields_autoplaced)
    (property "Reference" "C105" (id 0) (at 90.297 64.1413 90)
      (effects (font (size 1.524 1.524)) (justify left))
    )
    (property "Value" "C_4u7_0805" (id 1) (at 83.947 64.135 0)
      (effects (font (size 1.524 1.524)) hide)
    )
    (property "Footprint" "sa800u-baseboard-hw-footprints:C_0805_2012Metric" (id 2) (at 92.837 69.215 0)
      (effects (font (size 1.524 1.524)) (justify left) hide)
    )
    (property "Datasheet" " " (id 3) (at 87.757 64.135 0)
      (effects (font (size 1.27 1.27)) hide)
    )
    (property "Manufacturer" "Walsin" (id 4) (at 97.917 69.215 0)
      (effects (font (size 1.524 1.524)) (justify left) hide)
    )
    (property "MPN" "0805X475K250CT" (id 5) (at 95.377 69.215 0)
      (effects (font (size 1.524 1.524)) (justify left) hide)
    )
    (property "Val" "4u7" (id 6) (at 90.297 67.3162 90)
      (effects (font (size 1.27 1.27)) (justify left))
    )
    (property "DNP" "DNP" (id 7) (at 90.297 69.8562 90)
      (effects (font (size 1.27 1.27)) (justify left))
    )
    (property "License" "Apache-2.0" (id 8) (at 64.897 84.455 0)
      (effects (font (size 1.27 1.27) (thickness 0.15)) (justify left bottom) hide)
    )
    (property "Author" "Antmicro" (id 9) (at 62.357 84.455 0)
      (effects (font (size 1.27 1.27) (thickness 0.15)) (justify left bottom) hide)
    )
    (property "Voltage" "" (id 10) (at 59.817 84.455 0)
      (effects (font (size 1.27 1.27)) (justify left bottom) hide)
    )
    (property "Dielectric" "" (id 11) (at 57.277 84.455 0)
      (effects (font (size 1.27 1.27)) (justify left bottom) hide)
    )
    (pin "1")
    (pin "2")
  )

  (symbol (lib_id "sa800u-baseboard-hw:GND") (at 99.441 64.262 0) (unit 1)
    (in_bom yes) (on_board yes) (fields_autoplaced)
    (property "Reference" "#PWR0175" (id 0) (at 99.441 70.612 0)
      (effects (font (size 1.27 1.27)) hide)
    )
    (property "Value" "GND" (id 1) (at 99.441 68.707 0))
    (property "Footprint" "" (id 2) (at 99.441 64.262 0)
      (effects (font (size 1.27 1.27)) hide)
    )
    (property "Datasheet" "" (id 3) (at 99.441 64.262 0)
      (effects (font (size 1.27 1.27)) hide)
    )
    (property "Author" "Antmicro" (id 4) (at 108.331 71.882 0)
      (effects (font (size 1.27 1.27) (thickness 0.15)) (justify left bottom) hide)
    )
    (property "License" "Apache-2.0" (id 5) (at 108.331 74.422 0)
      (effects (font (size 1.27 1.27) (thickness 0.15)) (justify left bottom) hide)
    )
    (pin "1")
  )

  (symbol (lib_id "sa800u-baseboard-hw:GND") (at 119.38 66.675 0) (unit 1)
    (in_bom yes) (on_board yes) (fields_autoplaced)
    (property "Reference" "#PWR0176" (id 0) (at 119.38 73.025 0)
      (effects (font (size 1.27 1.27)) hide)
    )
    (property "Value" "GND" (id 1) (at 119.38 71.12 0))
    (property "Footprint" "" (id 2) (at 119.38 66.675 0)
      (effects (font (size 1.27 1.27)) hide)
    )
    (property "Datasheet" "" (id 3) (at 119.38 66.675 0)
      (effects (font (size 1.27 1.27)) hide)
    )
    (property "Author" "Antmicro" (id 4) (at 128.27 74.295 0)
      (effects (font (size 1.27 1.27) (thickness 0.15)) (justify left bottom) hide)
    )
    (property "License" "Apache-2.0" (id 5) (at 128.27 76.835 0)
      (effects (font (size 1.27 1.27) (thickness 0.15)) (justify left bottom) hide)
    )
    (pin "1")
  )

  (symbol (lib_id "sa800u-baseboard-hw:GND") (at 87.757 69.215 0) (unit 1)
    (in_bom yes) (on_board yes) (fields_autoplaced)
    (property "Reference" "#PWR0172" (id 0) (at 87.757 75.565 0)
      (effects (font (size 1.27 1.27)) hide)
    )
    (property "Value" "GND" (id 1) (at 85.217 70.4849 0)
      (effects (font (size 1.27 1.27)) (justify right))
    )
    (property "Footprint" "" (id 2) (at 87.757 69.215 0)
      (effects (font (size 1.27 1.27)) hide)
    )
    (property "Datasheet" "" (id 3) (at 87.757 69.215 0)
      (effects (font (size 1.27 1.27)) hide)
    )
    (property "Author" "Antmicro" (id 4) (at 96.647 76.835 0)
      (effects (font (size 1.27 1.27) (thickness 0.15)) (justify left bottom) hide)
    )
    (property "License" "Apache-2.0" (id 5) (at 96.647 79.375 0)
      (effects (font (size 1.27 1.27) (thickness 0.15)) (justify left bottom) hide)
    )
    (pin "1")
  )

  (symbol (lib_id "sa800u-baseboard-hw:R_0R_0603") (at 135.255 53.213 90) (unit 1)
    (in_bom yes) (on_board yes)
    (property "Reference" "R85" (id 0) (at 133.35 48.133 90)
      (effects (font (size 1.524 1.524)) (justify left))
    )
    (property "Value" "R_0R_0603" (id 1) (at 139.065 53.213 0)
      (effects (font (size 1.524 1.524)) hide)
    )
    (property "Footprint" "sa800u-baseboard-hw-footprints:R_0603_1608Metric" (id 2) (at 130.175 48.133 0)
      (effects (font (size 1.524 1.524)) (justify left) hide)
    )
    (property "Datasheet" "https://www.bourns.com/docs/product-datasheets/cr.pdf?sfvrsn=574d41f6_14" (id 3) (at 135.255 53.213 0)
      (effects (font (size 1.27 1.27)) hide)
    )
    (property "Manufacturer" "Bourns" (id 4) (at 125.095 48.133 0)
      (effects (font (size 1.524 1.524)) (justify left) hide)
    )
    (property "MPN" "CR0603-J/-000ELF" (id 5) (at 127.635 48.133 0)
      (effects (font (size 1.524 1.524)) (justify left) hide)
    )
    (property "Val" "0R" (id 6) (at 133.35 51.3079 90)
      (effects (font (size 1.27 1.27)) (justify left))
    )
    (property "DNP" "DNP" (id 7) (at 135.382 52.705 0)
      (effects (font (size 1.27 1.27)) (justify left))
    )
    (property "License" "Apache-2.0" (id 8) (at 160.655 32.893 0)
      (effects (font (size 1.27 1.27) (thickness 0.15)) (justify left bottom) hide)
    )
    (property "Author" "Antmicro" (id 9) (at 163.195 32.893 0)
      (effects (font (size 1.27 1.27) (thickness 0.15)) (justify left bottom) hide)
    )
    (property "Tolerance" "~" (id 10) (at 145.415 32.893 0)
      (effects (font (size 1.27 1.27)) (justify left bottom) hide)
    )
    (property "Current" "1A" (id 11) (at 165.735 32.893 0)
      (effects (font (size 1.27 1.27) (thickness 0.15)) (justify left bottom) hide)
    )
    (pin "1")
    (pin "2")
  )

  (symbol (lib_id "sa800u-baseboard-hw:R_0R_0603") (at 135.255 45.593 90) (unit 1)
    (in_bom yes) (on_board yes) (fields_autoplaced)
    (property "Reference" "R84" (id 0) (at 137.16 41.783 90)
      (effects (font (size 1.524 1.524)) (justify right))
    )
    (property "Value" "R_0R_0603" (id 1) (at 139.065 45.593 0)
      (effects (font (size 1.524 1.524)) hide)
    )
    (property "Footprint" "sa800u-baseboard-hw-footprints:R_0603_1608Metric" (id 2) (at 130.175 40.513 0)
      (effects (font (size 1.524 1.524)) (justify left) hide)
    )
    (property "Datasheet" "https://www.bourns.com/docs/product-datasheets/cr.pdf?sfvrsn=574d41f6_14" (id 3) (at 135.255 45.593 0)
      (effects (font (size 1.27 1.27)) hide)
    )
    (property "Manufacturer" "Bourns" (id 4) (at 125.095 40.513 0)
      (effects (font (size 1.524 1.524)) (justify left) hide)
    )
    (property "MPN" "CR0603-J/-000ELF" (id 5) (at 127.635 40.513 0)
      (effects (font (size 1.524 1.524)) (justify left) hide)
    )
    (property "Val" "0R" (id 6) (at 137.16 44.9579 90)
      (effects (font (size 1.27 1.27)) (justify right))
    )
    (property "License" "Apache-2.0" (id 7) (at 160.655 25.273 0)
      (effects (font (size 1.27 1.27) (thickness 0.15)) (justify left bottom) hide)
    )
    (property "Author" "Antmicro" (id 8) (at 163.195 25.273 0)
      (effects (font (size 1.27 1.27) (thickness 0.15)) (justify left bottom) hide)
    )
    (property "Tolerance" "~" (id 9) (at 145.415 25.273 0)
      (effects (font (size 1.27 1.27)) (justify left bottom) hide)
    )
    (property "Current" "1A" (id 10) (at 165.735 25.273 0)
      (effects (font (size 1.27 1.27) (thickness 0.15)) (justify left bottom) hide)
    )
    (pin "1")
    (pin "2")
  )

  (symbol (lib_id "sa800u-baseboard-hw:NTS0102_XSON") (at 125.73 236.22 0) (unit 1)
    (in_bom yes) (on_board yes) (fields_autoplaced)
    (property "Reference" "U13" (id 0) (at 135.89 228.6 0))
    (property "Value" "NTS0102_XSON" (id 1) (at 135.89 231.14 0))
    (property "Footprint" "sa800u-baseboard-hw-footprints:XSON-8_1x1.95mm_P0.5mm" (id 2) (at 123.19 223.52 0)
      (effects (font (size 1.27 1.27)) hide)
    )
    (property "Datasheet" "http://www.farnell.com/datasheets/1760723.pdf" (id 3) (at 142.24 217.17 0)
      (effects (font (size 1.27 1.27)) hide)
    )
    (property "MPN" "NTS0102GT" (id 4) (at 125.73 223.139 0)
      (effects (font (size 1.27 1.27)) hide)
    )
    (property "Manufacturer" "NXP" (id 5) (at 125.73 225.4504 0)
      (effects (font (size 1.27 1.27)) hide)
    )
    (property "Author" "Antmicro" (id 6) (at 161.29 254 0)
      (effects (font (size 1.27 1.27) (thickness 0.15)) (justify left bottom) hide)
    )
    (property "License" "Apache-2.0" (id 7) (at 161.29 256.54 0)
      (effects (font (size 1.27 1.27) (thickness 0.15)) (justify left bottom) hide)
    )
    (pin "1")
    (pin "2")
    (pin "3")
    (pin "4")
    (pin "5")
    (pin "6")
    (pin "7")
    (pin "8")
  )

  (symbol (lib_id "sa800u-baseboard-hw:C_100n_0402") (at 90.17 229.87 270) (unit 1)
    (in_bom yes) (on_board yes) (fields_autoplaced)
    (property "Reference" "C106" (id 0) (at 92.583 231.1463 90)
      (effects (font (size 1.524 1.524)) (justify left))
    )
    (property "Value" "C_100n_0402" (id 1) (at 86.36 229.87 0)
      (effects (font (size 1.524 1.524)) hide)
    )
    (property "Footprint" "sa800u-baseboard-hw-footprints:C_0402_1005Metric" (id 2) (at 95.25 234.95 0)
      (effects (font (size 1.524 1.524)) (justify left) hide)
    )
    (property "Datasheet" "https://search.murata.co.jp/Ceramy/image/img/A01X/G101/ENG/GRM155R61H104KE14-01.pdf" (id 3) (at 90.17 229.87 0)
      (effects (font (size 1.27 1.27)) hide)
    )
    (property "Manufacturer" "Murata" (id 4) (at 100.33 234.95 0)
      (effects (font (size 1.524 1.524)) (justify left) hide)
    )
    (property "MPN" "GRM155R61H104KE14D" (id 5) (at 97.79 234.95 0)
      (effects (font (size 1.524 1.524)) (justify left) hide)
    )
    (property "Val" "100n" (id 6) (at 92.583 234.3212 90)
      (effects (font (size 1.27 1.27)) (justify left))
    )
    (property "License" "Apache-2.0" (id 7) (at 67.31 250.19 0)
      (effects (font (size 1.27 1.27) (thickness 0.15)) (justify left bottom) hide)
    )
    (property "Author" "Antmicro" (id 8) (at 64.77 250.19 0)
      (effects (font (size 1.27 1.27) (thickness 0.15)) (justify left bottom) hide)
    )
    (property "Voltage" "50V" (id 9) (at 62.23 250.19 0)
      (effects (font (size 1.27 1.27)) (justify left bottom) hide)
    )
    (property "Dielectric" "X5R" (id 10) (at 59.69 250.19 0)
      (effects (font (size 1.27 1.27)) (justify left bottom) hide)
    )
    (pin "1")
    (pin "2")
  )

  (symbol (lib_id "sa800u-baseboard-hw:GND") (at 90.17 234.95 0) (unit 1)
    (in_bom yes) (on_board yes) (fields_autoplaced)
    (property "Reference" "#PWR0173" (id 0) (at 90.17 241.3 0)
      (effects (font (size 1.27 1.27)) hide)
    )
    (property "Value" "GND" (id 1) (at 87.63 236.2199 0)
      (effects (font (size 1.27 1.27)) (justify right))
    )
    (property "Footprint" "" (id 2) (at 90.17 234.95 0)
      (effects (font (size 1.27 1.27)) hide)
    )
    (property "Datasheet" "" (id 3) (at 90.17 234.95 0)
      (effects (font (size 1.27 1.27)) hide)
    )
    (property "Author" "Antmicro" (id 4) (at 99.06 242.57 0)
      (effects (font (size 1.27 1.27) (thickness 0.15)) (justify left bottom) hide)
    )
    (property "License" "Apache-2.0" (id 5) (at 99.06 245.11 0)
      (effects (font (size 1.27 1.27) (thickness 0.15)) (justify left bottom) hide)
    )
    (pin "1")
  )

  (symbol (lib_id "sa800u-baseboard-hw:R_2k_0402") (at 113.665 236.347 90) (unit 1)
    (in_bom yes) (on_board yes) (fields_autoplaced)
    (property "Reference" "R82" (id 0) (at 115.57 232.537 90)
      (effects (font (size 1.524 1.524)) (justify right))
    )
    (property "Value" "R_2k_0402" (id 1) (at 117.475 236.347 0)
      (effects (font (size 1.524 1.524)) hide)
    )
    (property "Footprint" "sa800u-baseboard-hw-footprints:R_0402_1005Metric" (id 2) (at 108.585 231.267 0)
      (effects (font (size 1.524 1.524)) (justify left) hide)
    )
    (property "Datasheet" "https://www.bourns.com/docs/product-datasheets/cr.pdf" (id 3) (at 113.665 236.347 0)
      (effects (font (size 1.27 1.27)) hide)
    )
    (property "Manufacturer" "Bourns" (id 4) (at 103.505 231.267 0)
      (effects (font (size 1.524 1.524)) (justify left) hide)
    )
    (property "MPN" "CR0402-FX-2001GLF" (id 5) (at 106.045 231.267 0)
      (effects (font (size 1.524 1.524)) (justify left) hide)
    )
    (property "Val" "2k" (id 6) (at 115.57 235.7119 90)
      (effects (font (size 1.27 1.27)) (justify right))
    )
    (property "License" "Apache-2.0" (id 7) (at 139.065 216.027 0)
      (effects (font (size 1.27 1.27) (thickness 0.15)) (justify left bottom) hide)
    )
    (property "Author" "Antmicro" (id 8) (at 141.605 216.027 0)
      (effects (font (size 1.27 1.27) (thickness 0.15)) (justify left bottom) hide)
    )
    (property "Tolerance" "1%" (id 9) (at 123.825 216.027 0)
      (effects (font (size 1.27 1.27)) (justify left bottom) hide)
    )
    (pin "1")
    (pin "2")
  )

  (symbol (lib_id "sa800u-baseboard-hw:C_100n_0402") (at 181.61 229.87 90) (mirror x) (unit 1)
    (in_bom yes) (on_board yes) (fields_autoplaced)
    (property "Reference" "C109" (id 0) (at 184.15 231.1463 90)
      (effects (font (size 1.524 1.524)) (justify right))
    )
    (property "Value" "C_100n_0402" (id 1) (at 185.42 229.87 0)
      (effects (font (size 1.524 1.524)) hide)
    )
    (property "Footprint" "sa800u-baseboard-hw-footprints:C_0402_1005Metric" (id 2) (at 176.53 234.95 0)
      (effects (font (size 1.524 1.524)) (justify left) hide)
    )
    (property "Datasheet" "https://search.murata.co.jp/Ceramy/image/img/A01X/G101/ENG/GRM155R61H104KE14-01.pdf" (id 3) (at 181.61 229.87 0)
      (effects (font (size 1.27 1.27)) hide)
    )
    (property "Manufacturer" "Murata" (id 4) (at 171.45 234.95 0)
      (effects (font (size 1.524 1.524)) (justify left) hide)
    )
    (property "MPN" "GRM155R61H104KE14D" (id 5) (at 173.99 234.95 0)
      (effects (font (size 1.524 1.524)) (justify left) hide)
    )
    (property "Val" "100n" (id 6) (at 184.15 234.3212 90)
      (effects (font (size 1.27 1.27)) (justify right))
    )
    (property "License" "Apache-2.0" (id 7) (at 204.47 250.19 0)
      (effects (font (size 1.27 1.27) (thickness 0.15)) (justify left bottom) hide)
    )
    (property "Author" "Antmicro" (id 8) (at 207.01 250.19 0)
      (effects (font (size 1.27 1.27) (thickness 0.15)) (justify left bottom) hide)
    )
    (property "Voltage" "50V" (id 9) (at 209.55 250.19 0)
      (effects (font (size 1.27 1.27)) (justify left bottom) hide)
    )
    (property "Dielectric" "X5R" (id 10) (at 212.09 250.19 0)
      (effects (font (size 1.27 1.27)) (justify left bottom) hide)
    )
    (pin "1")
    (pin "2")
  )

  (symbol (lib_id "sa800u-baseboard-hw:GND") (at 181.61 234.95 0) (mirror y) (unit 1)
    (in_bom yes) (on_board yes) (fields_autoplaced)
    (property "Reference" "#PWR0179" (id 0) (at 181.61 241.3 0)
      (effects (font (size 1.27 1.27)) hide)
    )
    (property "Value" "GND" (id 1) (at 181.61 240.03 0))
    (property "Footprint" "" (id 2) (at 181.61 234.95 0)
      (effects (font (size 1.27 1.27)) hide)
    )
    (property "Datasheet" "" (id 3) (at 181.61 234.95 0)
      (effects (font (size 1.27 1.27)) hide)
    )
    (property "Author" "Antmicro" (id 4) (at 172.72 242.57 0)
      (effects (font (size 1.27 1.27) (thickness 0.15)) (justify left bottom) hide)
    )
    (property "License" "Apache-2.0" (id 5) (at 172.72 245.11 0)
      (effects (font (size 1.27 1.27) (thickness 0.15)) (justify left bottom) hide)
    )
    (pin "1")
  )

  (symbol (lib_id "sa800u-baseboard-hw:GND") (at 147.32 245.11 0) (mirror y) (unit 1)
    (in_bom yes) (on_board yes) (fields_autoplaced)
    (property "Reference" "#PWR0177" (id 0) (at 147.32 251.46 0)
      (effects (font (size 1.27 1.27)) hide)
    )
    (property "Value" "GND" (id 1) (at 147.32 250.19 0))
    (property "Footprint" "" (id 2) (at 147.32 245.11 0)
      (effects (font (size 1.27 1.27)) hide)
    )
    (property "Datasheet" "" (id 3) (at 147.32 245.11 0)
      (effects (font (size 1.27 1.27)) hide)
    )
    (property "Author" "Antmicro" (id 4) (at 138.43 252.73 0)
      (effects (font (size 1.27 1.27) (thickness 0.15)) (justify left bottom) hide)
    )
    (property "License" "Apache-2.0" (id 5) (at 138.43 255.27 0)
      (effects (font (size 1.27 1.27) (thickness 0.15)) (justify left bottom) hide)
    )
    (pin "1")
  )

  (symbol (lib_id "sa800u-baseboard-hw:R_2k_0402") (at 111.125 236.347 90) (unit 1)
    (in_bom yes) (on_board yes) (fields_autoplaced)
    (property "Reference" "R80" (id 0) (at 109.22 232.537 90)
      (effects (font (size 1.524 1.524)) (justify left))
    )
    (property "Value" "R_2k_0402" (id 1) (at 114.935 236.347 0)
      (effects (font (size 1.524 1.524)) hide)
    )
    (property "Footprint" "sa800u-baseboard-hw-footprints:R_0402_1005Metric" (id 2) (at 106.045 231.267 0)
      (effects (font (size 1.524 1.524)) (justify left) hide)
    )
    (property "Datasheet" "https://www.bourns.com/docs/product-datasheets/cr.pdf" (id 3) (at 111.125 236.347 0)
      (effects (font (size 1.27 1.27)) hide)
    )
    (property "Manufacturer" "Bourns" (id 4) (at 100.965 231.267 0)
      (effects (font (size 1.524 1.524)) (justify left) hide)
    )
    (property "MPN" "CR0402-FX-2001GLF" (id 5) (at 103.505 231.267 0)
      (effects (font (size 1.524 1.524)) (justify left) hide)
    )
    (property "Val" "2k" (id 6) (at 109.22 235.7119 90)
      (effects (font (size 1.27 1.27)) (justify left))
    )
    (property "License" "Apache-2.0" (id 7) (at 136.525 216.027 0)
      (effects (font (size 1.27 1.27) (thickness 0.15)) (justify left bottom) hide)
    )
    (property "Author" "Antmicro" (id 8) (at 139.065 216.027 0)
      (effects (font (size 1.27 1.27) (thickness 0.15)) (justify left bottom) hide)
    )
    (property "Tolerance" "1%" (id 9) (at 121.285 216.027 0)
      (effects (font (size 1.27 1.27)) (justify left bottom) hide)
    )
    (pin "1")
    (pin "2")
  )

  (symbol (lib_id "sa800u-baseboard-hw:R_2k_0402") (at 158.115 235.839 270) (mirror x) (unit 1)
    (in_bom yes) (on_board yes) (fields_autoplaced)
    (property "Reference" "R86" (id 0) (at 156.21 232.029 90)
      (effects (font (size 1.524 1.524)) (justify right))
    )
    (property "Value" "R_2k_0402" (id 1) (at 154.305 235.839 0)
      (effects (font (size 1.524 1.524)) hide)
    )
    (property "Footprint" "sa800u-baseboard-hw-footprints:R_0402_1005Metric" (id 2) (at 163.195 230.759 0)
      (effects (font (size 1.524 1.524)) (justify left) hide)
    )
    (property "Datasheet" "https://www.bourns.com/docs/product-datasheets/cr.pdf" (id 3) (at 158.115 235.839 0)
      (effects (font (size 1.27 1.27)) hide)
    )
    (property "Manufacturer" "Bourns" (id 4) (at 168.275 230.759 0)
      (effects (font (size 1.524 1.524)) (justify left) hide)
    )
    (property "MPN" "CR0402-FX-2001GLF" (id 5) (at 165.735 230.759 0)
      (effects (font (size 1.524 1.524)) (justify left) hide)
    )
    (property "Val" "2k" (id 6) (at 156.21 235.2039 90)
      (effects (font (size 1.27 1.27)) (justify right))
    )
    (property "License" "Apache-2.0" (id 7) (at 132.715 215.519 0)
      (effects (font (size 1.27 1.27) (thickness 0.15)) (justify left bottom) hide)
    )
    (property "Author" "Antmicro" (id 8) (at 130.175 215.519 0)
      (effects (font (size 1.27 1.27) (thickness 0.15)) (justify left bottom) hide)
    )
    (property "Tolerance" "1%" (id 9) (at 147.955 215.519 0)
      (effects (font (size 1.27 1.27)) (justify left bottom) hide)
    )
    (pin "1")
    (pin "2")
  )

  (symbol (lib_id "sa800u-baseboard-hw:R_2k_0402") (at 160.655 235.839 270) (mirror x) (unit 1)
    (in_bom yes) (on_board yes) (fields_autoplaced)
    (property "Reference" "R88" (id 0) (at 162.56 232.029 90)
      (effects (font (size 1.524 1.524)) (justify left))
    )
    (property "Value" "R_2k_0402" (id 1) (at 156.845 235.839 0)
      (effects (font (size 1.524 1.524)) hide)
    )
    (property "Footprint" "sa800u-baseboard-hw-footprints:R_0402_1005Metric" (id 2) (at 165.735 230.759 0)
      (effects (font (size 1.524 1.524)) (justify left) hide)
    )
    (property "Datasheet" "https://www.bourns.com/docs/product-datasheets/cr.pdf" (id 3) (at 160.655 235.839 0)
      (effects (font (size 1.27 1.27)) hide)
    )
    (property "Manufacturer" "Bourns" (id 4) (at 170.815 230.759 0)
      (effects (font (size 1.524 1.524)) (justify left) hide)
    )
    (property "MPN" "CR0402-FX-2001GLF" (id 5) (at 168.275 230.759 0)
      (effects (font (size 1.524 1.524)) (justify left) hide)
    )
    (property "Val" "2k" (id 6) (at 162.56 235.2039 90)
      (effects (font (size 1.27 1.27)) (justify left))
    )
    (property "License" "Apache-2.0" (id 7) (at 135.255 215.519 0)
      (effects (font (size 1.27 1.27) (thickness 0.15)) (justify left bottom) hide)
    )
    (property "Author" "Antmicro" (id 8) (at 132.715 215.519 0)
      (effects (font (size 1.27 1.27) (thickness 0.15)) (justify left bottom) hide)
    )
    (property "Tolerance" "1%" (id 9) (at 150.495 215.519 0)
      (effects (font (size 1.27 1.27)) (justify left bottom) hide)
    )
    (pin "1")
    (pin "2")
  )

  (symbol (lib_id "sa800u-baseboard-hw:NTS0102_XSON") (at 125.73 260.985 0) (unit 1)
    (in_bom yes) (on_board yes) (fields_autoplaced)
    (property "Reference" "U14" (id 0) (at 135.89 274.32 0))
    (property "Value" "NTS0102_XSON" (id 1) (at 135.89 276.86 0))
    (property "Footprint" "sa800u-baseboard-hw-footprints:XSON-8_1x1.95mm_P0.5mm" (id 2) (at 123.19 248.285 0)
      (effects (font (size 1.27 1.27)) hide)
    )
    (property "Datasheet" "http://www.farnell.com/datasheets/1760723.pdf" (id 3) (at 142.24 241.935 0)
      (effects (font (size 1.27 1.27)) hide)
    )
    (property "MPN" "NTS0102GT" (id 4) (at 125.73 247.904 0)
      (effects (font (size 1.27 1.27)) hide)
    )
    (property "Manufacturer" "NXP" (id 5) (at 125.73 250.2154 0)
      (effects (font (size 1.27 1.27)) hide)
    )
    (property "Author" "Antmicro" (id 6) (at 161.29 278.765 0)
      (effects (font (size 1.27 1.27) (thickness 0.15)) (justify left bottom) hide)
    )
    (property "License" "Apache-2.0" (id 7) (at 161.29 281.305 0)
      (effects (font (size 1.27 1.27) (thickness 0.15)) (justify left bottom) hide)
    )
    (pin "1")
    (pin "2")
    (pin "3")
    (pin "4")
    (pin "5")
    (pin "6")
    (pin "7")
    (pin "8")
  )

  (symbol (lib_id "sa800u-baseboard-hw:C_100n_0402") (at 90.17 254.635 270) (unit 1)
    (in_bom yes) (on_board yes) (fields_autoplaced)
    (property "Reference" "C107" (id 0) (at 92.71 255.9113 90)
      (effects (font (size 1.524 1.524)) (justify left))
    )
    (property "Value" "C_100n_0402" (id 1) (at 86.36 254.635 0)
      (effects (font (size 1.524 1.524)) hide)
    )
    (property "Footprint" "sa800u-baseboard-hw-footprints:C_0402_1005Metric" (id 2) (at 95.25 259.715 0)
      (effects (font (size 1.524 1.524)) (justify left) hide)
    )
    (property "Datasheet" "https://search.murata.co.jp/Ceramy/image/img/A01X/G101/ENG/GRM155R61H104KE14-01.pdf" (id 3) (at 90.17 254.635 0)
      (effects (font (size 1.27 1.27)) hide)
    )
    (property "Manufacturer" "Murata" (id 4) (at 100.33 259.715 0)
      (effects (font (size 1.524 1.524)) (justify left) hide)
    )
    (property "MPN" "GRM155R61H104KE14D" (id 5) (at 97.79 259.715 0)
      (effects (font (size 1.524 1.524)) (justify left) hide)
    )
    (property "Val" "100n" (id 6) (at 92.71 259.0862 90)
      (effects (font (size 1.27 1.27)) (justify left))
    )
    (property "License" "Apache-2.0" (id 7) (at 67.31 274.955 0)
      (effects (font (size 1.27 1.27) (thickness 0.15)) (justify left bottom) hide)
    )
    (property "Author" "Antmicro" (id 8) (at 64.77 274.955 0)
      (effects (font (size 1.27 1.27) (thickness 0.15)) (justify left bottom) hide)
    )
    (property "Voltage" "50V" (id 9) (at 62.23 274.955 0)
      (effects (font (size 1.27 1.27)) (justify left bottom) hide)
    )
    (property "Dielectric" "X5R" (id 10) (at 59.69 274.955 0)
      (effects (font (size 1.27 1.27)) (justify left bottom) hide)
    )
    (pin "1")
    (pin "2")
  )

  (symbol (lib_id "sa800u-baseboard-hw:GND") (at 90.17 259.715 0) (unit 1)
    (in_bom yes) (on_board yes) (fields_autoplaced)
    (property "Reference" "#PWR0174" (id 0) (at 90.17 266.065 0)
      (effects (font (size 1.27 1.27)) hide)
    )
    (property "Value" "GND" (id 1) (at 87.63 260.9849 0)
      (effects (font (size 1.27 1.27)) (justify right))
    )
    (property "Footprint" "" (id 2) (at 90.17 259.715 0)
      (effects (font (size 1.27 1.27)) hide)
    )
    (property "Datasheet" "" (id 3) (at 90.17 259.715 0)
      (effects (font (size 1.27 1.27)) hide)
    )
    (property "Author" "Antmicro" (id 4) (at 99.06 267.335 0)
      (effects (font (size 1.27 1.27) (thickness 0.15)) (justify left bottom) hide)
    )
    (property "License" "Apache-2.0" (id 5) (at 99.06 269.875 0)
      (effects (font (size 1.27 1.27) (thickness 0.15)) (justify left bottom) hide)
    )
    (pin "1")
  )

  (symbol (lib_id "sa800u-baseboard-hw:R_2k_0402") (at 113.665 260.223 90) (unit 1)
    (in_bom yes) (on_board yes) (fields_autoplaced)
    (property "Reference" "R83" (id 0) (at 115.57 256.413 90)
      (effects (font (size 1.524 1.524)) (justify right))
    )
    (property "Value" "R_2k_0402" (id 1) (at 117.475 260.223 0)
      (effects (font (size 1.524 1.524)) hide)
    )
    (property "Footprint" "sa800u-baseboard-hw-footprints:R_0402_1005Metric" (id 2) (at 108.585 255.143 0)
      (effects (font (size 1.524 1.524)) (justify left) hide)
    )
    (property "Datasheet" "https://www.bourns.com/docs/product-datasheets/cr.pdf" (id 3) (at 113.665 260.223 0)
      (effects (font (size 1.27 1.27)) hide)
    )
    (property "Manufacturer" "Bourns" (id 4) (at 103.505 255.143 0)
      (effects (font (size 1.524 1.524)) (justify left) hide)
    )
    (property "MPN" "CR0402-FX-2001GLF" (id 5) (at 106.045 255.143 0)
      (effects (font (size 1.524 1.524)) (justify left) hide)
    )
    (property "Val" "2k" (id 6) (at 115.57 259.5879 90)
      (effects (font (size 1.27 1.27)) (justify right))
    )
    (property "License" "Apache-2.0" (id 7) (at 139.065 239.903 0)
      (effects (font (size 1.27 1.27) (thickness 0.15)) (justify left bottom) hide)
    )
    (property "Author" "Antmicro" (id 8) (at 141.605 239.903 0)
      (effects (font (size 1.27 1.27) (thickness 0.15)) (justify left bottom) hide)
    )
    (property "Tolerance" "1%" (id 9) (at 123.825 239.903 0)
      (effects (font (size 1.27 1.27)) (justify left bottom) hide)
    )
    (pin "1")
    (pin "2")
  )

  (symbol (lib_id "sa800u-baseboard-hw:C_100n_0402") (at 181.61 254.762 90) (mirror x) (unit 1)
    (in_bom yes) (on_board yes) (fields_autoplaced)
    (property "Reference" "C110" (id 0) (at 185.166 256.0383 90)
      (effects (font (size 1.524 1.524)) (justify right))
    )
    (property "Value" "C_100n_0402" (id 1) (at 185.42 254.762 0)
      (effects (font (size 1.524 1.524)) hide)
    )
    (property "Footprint" "sa800u-baseboard-hw-footprints:C_0402_1005Metric" (id 2) (at 176.53 259.842 0)
      (effects (font (size 1.524 1.524)) (justify left) hide)
    )
    (property "Datasheet" "https://search.murata.co.jp/Ceramy/image/img/A01X/G101/ENG/GRM155R61H104KE14-01.pdf" (id 3) (at 181.61 254.762 0)
      (effects (font (size 1.27 1.27)) hide)
    )
    (property "Manufacturer" "Murata" (id 4) (at 171.45 259.842 0)
      (effects (font (size 1.524 1.524)) (justify left) hide)
    )
    (property "MPN" "GRM155R61H104KE14D" (id 5) (at 173.99 259.842 0)
      (effects (font (size 1.524 1.524)) (justify left) hide)
    )
    (property "Val" "100n" (id 6) (at 185.166 259.2132 90)
      (effects (font (size 1.27 1.27)) (justify right))
    )
    (property "License" "Apache-2.0" (id 7) (at 204.47 275.082 0)
      (effects (font (size 1.27 1.27) (thickness 0.15)) (justify left bottom) hide)
    )
    (property "Author" "Antmicro" (id 8) (at 207.01 275.082 0)
      (effects (font (size 1.27 1.27) (thickness 0.15)) (justify left bottom) hide)
    )
    (property "Voltage" "50V" (id 9) (at 209.55 275.082 0)
      (effects (font (size 1.27 1.27)) (justify left bottom) hide)
    )
    (property "Dielectric" "X5R" (id 10) (at 212.09 275.082 0)
      (effects (font (size 1.27 1.27)) (justify left bottom) hide)
    )
    (pin "1")
    (pin "2")
  )

  (symbol (lib_id "sa800u-baseboard-hw:GND") (at 181.61 259.842 0) (mirror y) (unit 1)
    (in_bom yes) (on_board yes) (fields_autoplaced)
    (property "Reference" "#PWR0180" (id 0) (at 181.61 266.192 0)
      (effects (font (size 1.27 1.27)) hide)
    )
    (property "Value" "GND" (id 1) (at 181.61 264.287 0))
    (property "Footprint" "" (id 2) (at 181.61 259.842 0)
      (effects (font (size 1.27 1.27)) hide)
    )
    (property "Datasheet" "" (id 3) (at 181.61 259.842 0)
      (effects (font (size 1.27 1.27)) hide)
    )
    (property "Author" "Antmicro" (id 4) (at 172.72 267.462 0)
      (effects (font (size 1.27 1.27) (thickness 0.15)) (justify left bottom) hide)
    )
    (property "License" "Apache-2.0" (id 5) (at 172.72 270.002 0)
      (effects (font (size 1.27 1.27) (thickness 0.15)) (justify left bottom) hide)
    )
    (pin "1")
  )

  (symbol (lib_id "sa800u-baseboard-hw:GND") (at 147.32 269.875 0) (mirror y) (unit 1)
    (in_bom yes) (on_board yes) (fields_autoplaced)
    (property "Reference" "#PWR0178" (id 0) (at 147.32 276.225 0)
      (effects (font (size 1.27 1.27)) hide)
    )
    (property "Value" "GND" (id 1) (at 147.32 274.32 0))
    (property "Footprint" "" (id 2) (at 147.32 269.875 0)
      (effects (font (size 1.27 1.27)) hide)
    )
    (property "Datasheet" "" (id 3) (at 147.32 269.875 0)
      (effects (font (size 1.27 1.27)) hide)
    )
    (property "Author" "Antmicro" (id 4) (at 138.43 277.495 0)
      (effects (font (size 1.27 1.27) (thickness 0.15)) (justify left bottom) hide)
    )
    (property "License" "Apache-2.0" (id 5) (at 138.43 280.035 0)
      (effects (font (size 1.27 1.27) (thickness 0.15)) (justify left bottom) hide)
    )
    (pin "1")
  )

  (symbol (lib_id "sa800u-baseboard-hw:R_2k_0402") (at 111.125 260.223 90) (unit 1)
    (in_bom yes) (on_board yes) (fields_autoplaced)
    (property "Reference" "R81" (id 0) (at 109.22 256.413 90)
      (effects (font (size 1.524 1.524)) (justify left))
    )
    (property "Value" "R_2k_0402" (id 1) (at 114.935 260.223 0)
      (effects (font (size 1.524 1.524)) hide)
    )
    (property "Footprint" "sa800u-baseboard-hw-footprints:R_0402_1005Metric" (id 2) (at 106.045 255.143 0)
      (effects (font (size 1.524 1.524)) (justify left) hide)
    )
    (property "Datasheet" "https://www.bourns.com/docs/product-datasheets/cr.pdf" (id 3) (at 111.125 260.223 0)
      (effects (font (size 1.27 1.27)) hide)
    )
    (property "Manufacturer" "Bourns" (id 4) (at 100.965 255.143 0)
      (effects (font (size 1.524 1.524)) (justify left) hide)
    )
    (property "MPN" "CR0402-FX-2001GLF" (id 5) (at 103.505 255.143 0)
      (effects (font (size 1.524 1.524)) (justify left) hide)
    )
    (property "Val" "2k" (id 6) (at 109.22 259.5879 90)
      (effects (font (size 1.27 1.27)) (justify left))
    )
    (property "License" "Apache-2.0" (id 7) (at 136.525 239.903 0)
      (effects (font (size 1.27 1.27) (thickness 0.15)) (justify left bottom) hide)
    )
    (property "Author" "Antmicro" (id 8) (at 139.065 239.903 0)
      (effects (font (size 1.27 1.27) (thickness 0.15)) (justify left bottom) hide)
    )
    (property "Tolerance" "1%" (id 9) (at 121.285 239.903 0)
      (effects (font (size 1.27 1.27)) (justify left bottom) hide)
    )
    (pin "1")
    (pin "2")
  )

  (symbol (lib_id "sa800u-baseboard-hw:R_2k_0402") (at 158.115 260.731 270) (mirror x) (unit 1)
    (in_bom yes) (on_board yes) (fields_autoplaced)
    (property "Reference" "R87" (id 0) (at 156.21 256.921 90)
      (effects (font (size 1.524 1.524)) (justify right))
    )
    (property "Value" "R_2k_0402" (id 1) (at 154.305 260.731 0)
      (effects (font (size 1.524 1.524)) hide)
    )
    (property "Footprint" "sa800u-baseboard-hw-footprints:R_0402_1005Metric" (id 2) (at 163.195 255.651 0)
      (effects (font (size 1.524 1.524)) (justify left) hide)
    )
    (property "Datasheet" "https://www.bourns.com/docs/product-datasheets/cr.pdf" (id 3) (at 158.115 260.731 0)
      (effects (font (size 1.27 1.27)) hide)
    )
    (property "Manufacturer" "Bourns" (id 4) (at 168.275 255.651 0)
      (effects (font (size 1.524 1.524)) (justify left) hide)
    )
    (property "MPN" "CR0402-FX-2001GLF" (id 5) (at 165.735 255.651 0)
      (effects (font (size 1.524 1.524)) (justify left) hide)
    )
    (property "Val" "2k" (id 6) (at 156.21 260.0959 90)
      (effects (font (size 1.27 1.27)) (justify right))
    )
    (property "License" "Apache-2.0" (id 7) (at 132.715 240.411 0)
      (effects (font (size 1.27 1.27) (thickness 0.15)) (justify left bottom) hide)
    )
    (property "Author" "Antmicro" (id 8) (at 130.175 240.411 0)
      (effects (font (size 1.27 1.27) (thickness 0.15)) (justify left bottom) hide)
    )
    (property "Tolerance" "1%" (id 9) (at 147.955 240.411 0)
      (effects (font (size 1.27 1.27)) (justify left bottom) hide)
    )
    (pin "1")
    (pin "2")
  )

  (symbol (lib_id "sa800u-baseboard-hw:R_2k_0402") (at 160.655 260.731 270) (mirror x) (unit 1)
    (in_bom yes) (on_board yes) (fields_autoplaced)
    (property "Reference" "R89" (id 0) (at 162.56 256.921 90)
      (effects (font (size 1.524 1.524)) (justify left))
    )
    (property "Value" "R_2k_0402" (id 1) (at 156.845 260.731 0)
      (effects (font (size 1.524 1.524)) hide)
    )
    (property "Footprint" "sa800u-baseboard-hw-footprints:R_0402_1005Metric" (id 2) (at 165.735 255.651 0)
      (effects (font (size 1.524 1.524)) (justify left) hide)
    )
    (property "Datasheet" "https://www.bourns.com/docs/product-datasheets/cr.pdf" (id 3) (at 160.655 260.731 0)
      (effects (font (size 1.27 1.27)) hide)
    )
    (property "Manufacturer" "Bourns" (id 4) (at 170.815 255.651 0)
      (effects (font (size 1.524 1.524)) (justify left) hide)
    )
    (property "MPN" "CR0402-FX-2001GLF" (id 5) (at 168.275 255.651 0)
      (effects (font (size 1.524 1.524)) (justify left) hide)
    )
    (property "Val" "2k" (id 6) (at 162.56 260.0959 90)
      (effects (font (size 1.27 1.27)) (justify left))
    )
    (property "License" "Apache-2.0" (id 7) (at 135.255 240.411 0)
      (effects (font (size 1.27 1.27) (thickness 0.15)) (justify left bottom) hide)
    )
    (property "Author" "Antmicro" (id 8) (at 132.715 240.411 0)
      (effects (font (size 1.27 1.27) (thickness 0.15)) (justify left bottom) hide)
    )
    (property "Tolerance" "1%" (id 9) (at 150.495 240.411 0)
      (effects (font (size 1.27 1.27)) (justify left bottom) hide)
    )
    (pin "1")
    (pin "2")
  )

  (symbol (lib_id "sa800u-baseboard-hw:TP_0.75mm_SMD") (at 160.655 243.84 90) (mirror x) (unit 1)
    (in_bom yes) (on_board yes) (fields_autoplaced)
    (property "Reference" "TP37" (id 0) (at 162.56 247.0149 90)
      (effects (font (size 1.27 1.27)) (justify right))
    )
    (property "Value" "TP_0.75mm_SMD" (id 1) (at 163.195 243.84 0)
      (effects (font (size 1.27 1.27)) hide)
    )
    (property "Footprint" "sa800u-baseboard-hw-footprints:TP_SMD_0.75mm" (id 2) (at 155.575 248.92 0)
      (effects (font (size 1.524 1.524)) (justify left) hide)
    )
    (property "Datasheet" "" (id 3) (at 153.035 248.92 0)
      (effects (font (size 1.524 1.524)) (justify left) hide)
    )
    (property "MPN" "" (id 4) (at 175.895 261.62 0)
      (effects (font (size 1.27 1.27) (thickness 0.15)) (justify left bottom) hide)
    )
    (property "Manufacturer" "" (id 5) (at 178.435 261.62 0)
      (effects (font (size 1.27 1.27) (thickness 0.15)) (justify left bottom) hide)
    )
    (property "Author" "Antmicro" (id 6) (at 180.975 261.62 0)
      (effects (font (size 1.27 1.27) (thickness 0.15)) (justify left bottom) hide)
    )
    (property "License" "Apache-2.0" (id 7) (at 183.515 261.62 0)
      (effects (font (size 1.27 1.27) (thickness 0.15)) (justify left bottom) hide)
    )
    (pin "1")
  )

  (symbol (lib_id "sa800u-baseboard-hw:TP_0.75mm_SMD") (at 158.115 243.84 90) (mirror x) (unit 1)
    (in_bom yes) (on_board yes) (fields_autoplaced)
    (property "Reference" "TP35" (id 0) (at 155.702 247.0149 90)
      (effects (font (size 1.27 1.27)) (justify left))
    )
    (property "Value" "TP_0.75mm_SMD" (id 1) (at 160.655 243.84 0)
      (effects (font (size 1.27 1.27)) hide)
    )
    (property "Footprint" "sa800u-baseboard-hw-footprints:TP_SMD_0.75mm" (id 2) (at 153.035 248.92 0)
      (effects (font (size 1.524 1.524)) (justify left) hide)
    )
    (property "Datasheet" "" (id 3) (at 150.495 248.92 0)
      (effects (font (size 1.524 1.524)) (justify left) hide)
    )
    (property "MPN" "" (id 4) (at 173.355 261.62 0)
      (effects (font (size 1.27 1.27) (thickness 0.15)) (justify left bottom) hide)
    )
    (property "Manufacturer" "" (id 5) (at 175.895 261.62 0)
      (effects (font (size 1.27 1.27) (thickness 0.15)) (justify left bottom) hide)
    )
    (property "Author" "Antmicro" (id 6) (at 178.435 261.62 0)
      (effects (font (size 1.27 1.27) (thickness 0.15)) (justify left bottom) hide)
    )
    (property "License" "Apache-2.0" (id 7) (at 180.975 261.62 0)
      (effects (font (size 1.27 1.27) (thickness 0.15)) (justify left bottom) hide)
    )
    (pin "1")
  )

  (symbol (lib_id "sa800u-baseboard-hw:TP_0.75mm_SMD") (at 160.655 268.605 90) (mirror x) (unit 1)
    (in_bom yes) (on_board yes) (fields_autoplaced)
    (property "Reference" "TP38" (id 0) (at 162.56 271.7799 90)
      (effects (font (size 1.27 1.27)) (justify right))
    )
    (property "Value" "TP_0.75mm_SMD" (id 1) (at 163.195 268.605 0)
      (effects (font (size 1.27 1.27)) hide)
    )
    (property "Footprint" "sa800u-baseboard-hw-footprints:TP_SMD_0.75mm" (id 2) (at 155.575 273.685 0)
      (effects (font (size 1.524 1.524)) (justify left) hide)
    )
    (property "Datasheet" "" (id 3) (at 153.035 273.685 0)
      (effects (font (size 1.524 1.524)) (justify left) hide)
    )
    (property "MPN" "" (id 4) (at 175.895 286.385 0)
      (effects (font (size 1.27 1.27) (thickness 0.15)) (justify left bottom) hide)
    )
    (property "Manufacturer" "" (id 5) (at 178.435 286.385 0)
      (effects (font (size 1.27 1.27) (thickness 0.15)) (justify left bottom) hide)
    )
    (property "Author" "Antmicro" (id 6) (at 180.975 286.385 0)
      (effects (font (size 1.27 1.27) (thickness 0.15)) (justify left bottom) hide)
    )
    (property "License" "Apache-2.0" (id 7) (at 183.515 286.385 0)
      (effects (font (size 1.27 1.27) (thickness 0.15)) (justify left bottom) hide)
    )
    (pin "1")
  )

  (symbol (lib_id "sa800u-baseboard-hw:TP_0.75mm_SMD") (at 158.115 268.605 90) (mirror x) (unit 1)
    (in_bom yes) (on_board yes) (fields_autoplaced)
    (property "Reference" "TP36" (id 0) (at 156.21 271.7799 90)
      (effects (font (size 1.27 1.27)) (justify left))
    )
    (property "Value" "TP_0.75mm_SMD" (id 1) (at 160.655 268.605 0)
      (effects (font (size 1.27 1.27)) hide)
    )
    (property "Footprint" "sa800u-baseboard-hw-footprints:TP_SMD_0.75mm" (id 2) (at 153.035 273.685 0)
      (effects (font (size 1.524 1.524)) (justify left) hide)
    )
    (property "Datasheet" "" (id 3) (at 150.495 273.685 0)
      (effects (font (size 1.524 1.524)) (justify left) hide)
    )
    (property "MPN" "" (id 4) (at 173.355 286.385 0)
      (effects (font (size 1.27 1.27) (thickness 0.15)) (justify left bottom) hide)
    )
    (property "Manufacturer" "" (id 5) (at 175.895 286.385 0)
      (effects (font (size 1.27 1.27) (thickness 0.15)) (justify left bottom) hide)
    )
    (property "Author" "Antmicro" (id 6) (at 178.435 286.385 0)
      (effects (font (size 1.27 1.27) (thickness 0.15)) (justify left bottom) hide)
    )
    (property "License" "Apache-2.0" (id 7) (at 180.975 286.385 0)
      (effects (font (size 1.27 1.27) (thickness 0.15)) (justify left bottom) hide)
    )
    (pin "1")
  )

  (symbol (lib_id "sa800u-baseboard-hw:TP_0.75mm_SMD") (at 111.125 268.605 270) (unit 1)
    (in_bom yes) (on_board yes) (fields_autoplaced)
    (property "Reference" "TP30" (id 0) (at 109.474 271.7799 90)
      (effects (font (size 1.27 1.27)) (justify right))
    )
    (property "Value" "TP_0.75mm_SMD" (id 1) (at 108.585 268.605 0)
      (effects (font (size 1.27 1.27)) hide)
    )
    (property "Footprint" "sa800u-baseboard-hw-footprints:TP_SMD_0.75mm" (id 2) (at 116.205 273.685 0)
      (effects (font (size 1.524 1.524)) (justify left) hide)
    )
    (property "Datasheet" "" (id 3) (at 118.745 273.685 0)
      (effects (font (size 1.524 1.524)) (justify left) hide)
    )
    (property "MPN" "" (id 4) (at 95.885 286.385 0)
      (effects (font (size 1.27 1.27) (thickness 0.15)) (justify left bottom) hide)
    )
    (property "Manufacturer" "" (id 5) (at 93.345 286.385 0)
      (effects (font (size 1.27 1.27) (thickness 0.15)) (justify left bottom) hide)
    )
    (property "Author" "Antmicro" (id 6) (at 90.805 286.385 0)
      (effects (font (size 1.27 1.27) (thickness 0.15)) (justify left bottom) hide)
    )
    (property "License" "Apache-2.0" (id 7) (at 88.265 286.385 0)
      (effects (font (size 1.27 1.27) (thickness 0.15)) (justify left bottom) hide)
    )
    (pin "1")
  )

  (symbol (lib_id "sa800u-baseboard-hw:TP_0.75mm_SMD") (at 113.665 268.605 270) (unit 1)
    (in_bom yes) (on_board yes) (fields_autoplaced)
    (property "Reference" "TP32" (id 0) (at 115.697 271.7799 90)
      (effects (font (size 1.27 1.27)) (justify left))
    )
    (property "Value" "TP_0.75mm_SMD" (id 1) (at 111.125 268.605 0)
      (effects (font (size 1.27 1.27)) hide)
    )
    (property "Footprint" "sa800u-baseboard-hw-footprints:TP_SMD_0.75mm" (id 2) (at 118.745 273.685 0)
      (effects (font (size 1.524 1.524)) (justify left) hide)
    )
    (property "Datasheet" "" (id 3) (at 121.285 273.685 0)
      (effects (font (size 1.524 1.524)) (justify left) hide)
    )
    (property "MPN" "" (id 4) (at 98.425 286.385 0)
      (effects (font (size 1.27 1.27) (thickness 0.15)) (justify left bottom) hide)
    )
    (property "Manufacturer" "" (id 5) (at 95.885 286.385 0)
      (effects (font (size 1.27 1.27) (thickness 0.15)) (justify left bottom) hide)
    )
    (property "Author" "Antmicro" (id 6) (at 93.345 286.385 0)
      (effects (font (size 1.27 1.27) (thickness 0.15)) (justify left bottom) hide)
    )
    (property "License" "Apache-2.0" (id 7) (at 90.805 286.385 0)
      (effects (font (size 1.27 1.27) (thickness 0.15)) (justify left bottom) hide)
    )
    (pin "1")
  )

  (symbol (lib_id "sa800u-baseboard-hw:TP_0.75mm_SMD") (at 111.125 243.84 270) (unit 1)
    (in_bom yes) (on_board yes) (fields_autoplaced)
    (property "Reference" "TP29" (id 0) (at 109.22 247.0149 90)
      (effects (font (size 1.27 1.27)) (justify right))
    )
    (property "Value" "TP_0.75mm_SMD" (id 1) (at 108.585 243.84 0)
      (effects (font (size 1.27 1.27)) hide)
    )
    (property "Footprint" "sa800u-baseboard-hw-footprints:TP_SMD_0.75mm" (id 2) (at 116.205 248.92 0)
      (effects (font (size 1.524 1.524)) (justify left) hide)
    )
    (property "Datasheet" "" (id 3) (at 118.745 248.92 0)
      (effects (font (size 1.524 1.524)) (justify left) hide)
    )
    (property "MPN" "" (id 4) (at 95.885 261.62 0)
      (effects (font (size 1.27 1.27) (thickness 0.15)) (justify left bottom) hide)
    )
    (property "Manufacturer" "" (id 5) (at 93.345 261.62 0)
      (effects (font (size 1.27 1.27) (thickness 0.15)) (justify left bottom) hide)
    )
    (property "Author" "Antmicro" (id 6) (at 90.805 261.62 0)
      (effects (font (size 1.27 1.27) (thickness 0.15)) (justify left bottom) hide)
    )
    (property "License" "Apache-2.0" (id 7) (at 88.265 261.62 0)
      (effects (font (size 1.27 1.27) (thickness 0.15)) (justify left bottom) hide)
    )
    (pin "1")
  )

  (symbol (lib_id "sa800u-baseboard-hw:TP_0.75mm_SMD") (at 113.665 243.84 270) (unit 1)
    (in_bom yes) (on_board yes) (fields_autoplaced)
    (property "Reference" "TP31" (id 0) (at 115.57 247.0149 90)
      (effects (font (size 1.27 1.27)) (justify left))
    )
    (property "Value" "TP_0.75mm_SMD" (id 1) (at 111.125 243.84 0)
      (effects (font (size 1.27 1.27)) hide)
    )
    (property "Footprint" "sa800u-baseboard-hw-footprints:TP_SMD_0.75mm" (id 2) (at 118.745 248.92 0)
      (effects (font (size 1.524 1.524)) (justify left) hide)
    )
    (property "Datasheet" "" (id 3) (at 121.285 248.92 0)
      (effects (font (size 1.524 1.524)) (justify left) hide)
    )
    (property "MPN" "" (id 4) (at 98.425 261.62 0)
      (effects (font (size 1.27 1.27) (thickness 0.15)) (justify left bottom) hide)
    )
    (property "Manufacturer" "" (id 5) (at 95.885 261.62 0)
      (effects (font (size 1.27 1.27) (thickness 0.15)) (justify left bottom) hide)
    )
    (property "Author" "Antmicro" (id 6) (at 93.345 261.62 0)
      (effects (font (size 1.27 1.27) (thickness 0.15)) (justify left bottom) hide)
    )
    (property "License" "Apache-2.0" (id 7) (at 90.805 261.62 0)
      (effects (font (size 1.27 1.27) (thickness 0.15)) (justify left bottom) hide)
    )
    (pin "1")
  )

  (symbol (lib_id "sa800u-baseboard-hw:TP_0.75mm_SMD") (at 87.757 53.34 90) (unit 1)
    (in_bom yes) (on_board yes) (fields_autoplaced)
    (property "Reference" "TP28" (id 0) (at 90.297 50.1649 90)
      (effects (font (size 1.27 1.27)) (justify right))
    )
    (property "Value" "TP_0.75mm_SMD" (id 1) (at 90.297 53.34 0)
      (effects (font (size 1.27 1.27)) hide)
    )
    (property "Footprint" "sa800u-baseboard-hw-footprints:TP_SMD_0.75mm" (id 2) (at 82.677 48.26 0)
      (effects (font (size 1.524 1.524)) (justify left) hide)
    )
    (property "Datasheet" "" (id 3) (at 80.137 48.26 0)
      (effects (font (size 1.524 1.524)) (justify left) hide)
    )
    (property "MPN" "" (id 4) (at 102.997 35.56 0)
      (effects (font (size 1.27 1.27) (thickness 0.15)) (justify left bottom) hide)
    )
    (property "Manufacturer" "" (id 5) (at 105.537 35.56 0)
      (effects (font (size 1.27 1.27) (thickness 0.15)) (justify left bottom) hide)
    )
    (property "Author" "Antmicro" (id 6) (at 108.077 35.56 0)
      (effects (font (size 1.27 1.27) (thickness 0.15)) (justify left bottom) hide)
    )
    (property "License" "Apache-2.0" (id 7) (at 110.617 35.56 0)
      (effects (font (size 1.27 1.27) (thickness 0.15)) (justify left bottom) hide)
    )
    (pin "1")
  )

  (symbol (lib_id "sa800u-baseboard-hw:TP_0.75mm_SMD") (at 119.38 53.34 90) (unit 1)
    (in_bom yes) (on_board yes) (fields_autoplaced)
    (property "Reference" "TP33" (id 0) (at 120.777 50.1649 90)
      (effects (font (size 1.27 1.27)) (justify right))
    )
    (property "Value" "TP_0.75mm_SMD" (id 1) (at 121.92 53.34 0)
      (effects (font (size 1.27 1.27)) hide)
    )
    (property "Footprint" "sa800u-baseboard-hw-footprints:TP_SMD_0.75mm" (id 2) (at 114.3 48.26 0)
      (effects (font (size 1.524 1.524)) (justify left) hide)
    )
    (property "Datasheet" "" (id 3) (at 111.76 48.26 0)
      (effects (font (size 1.524 1.524)) (justify left) hide)
    )
    (property "MPN" "" (id 4) (at 134.62 35.56 0)
      (effects (font (size 1.27 1.27) (thickness 0.15)) (justify left bottom) hide)
    )
    (property "Manufacturer" "" (id 5) (at 137.16 35.56 0)
      (effects (font (size 1.27 1.27) (thickness 0.15)) (justify left bottom) hide)
    )
    (property "Author" "Antmicro" (id 6) (at 139.7 35.56 0)
      (effects (font (size 1.27 1.27) (thickness 0.15)) (justify left bottom) hide)
    )
    (property "License" "Apache-2.0" (id 7) (at 142.24 35.56 0)
      (effects (font (size 1.27 1.27) (thickness 0.15)) (justify left bottom) hide)
    )
    (pin "1")
  )

  (symbol (lib_id "sa800u-baseboard-hw:TP_0.75mm_SMD") (at 154.305 46.99 0) (unit 1)
    (in_bom yes) (on_board yes) (fields_autoplaced)
    (property "Reference" "TP34" (id 0) (at 159.639 46.9899 0)
      (effects (font (size 1.27 1.27)) (justify left))
    )
    (property "Value" "TP_0.75mm_SMD" (id 1) (at 154.305 49.53 0)
      (effects (font (size 1.27 1.27)) hide)
    )
    (property "Footprint" "sa800u-baseboard-hw-footprints:TP_SMD_0.75mm" (id 2) (at 159.385 41.91 0)
      (effects (font (size 1.524 1.524)) (justify left) hide)
    )
    (property "Datasheet" "" (id 3) (at 159.385 39.37 0)
      (effects (font (size 1.524 1.524)) (justify left) hide)
    )
    (property "MPN" "" (id 4) (at 172.085 62.23 0)
      (effects (font (size 1.27 1.27) (thickness 0.15)) (justify left bottom) hide)
    )
    (property "Manufacturer" "" (id 5) (at 172.085 64.77 0)
      (effects (font (size 1.27 1.27) (thickness 0.15)) (justify left bottom) hide)
    )
    (property "Author" "Antmicro" (id 6) (at 172.085 67.31 0)
      (effects (font (size 1.27 1.27) (thickness 0.15)) (justify left bottom) hide)
    )
    (property "License" "Apache-2.0" (id 7) (at 172.085 69.85 0)
      (effects (font (size 1.27 1.27) (thickness 0.15)) (justify left bottom) hide)
    )
    (pin "1")
  )

  (symbol (lib_id "sa800u-baseboard-hw:TP_0.75mm_SMD") (at 312.42 147.955 90) (unit 1)
    (in_bom yes) (on_board yes) (fields_autoplaced)
    (property "Reference" "TP40" (id 0) (at 309.88 144.7799 90)
      (effects (font (size 1.27 1.27)) (justify left))
    )
    (property "Value" "TP_0.75mm_SMD" (id 1) (at 314.96 147.955 0)
      (effects (font (size 1.27 1.27)) hide)
    )
    (property "Footprint" "sa800u-baseboard-hw-footprints:TP_SMD_0.75mm" (id 2) (at 307.34 142.875 0)
      (effects (font (size 1.524 1.524)) (justify left) hide)
    )
    (property "Datasheet" "" (id 3) (at 304.8 142.875 0)
      (effects (font (size 1.524 1.524)) (justify left) hide)
    )
    (property "MPN" "" (id 4) (at 327.66 130.175 0)
      (effects (font (size 1.27 1.27) (thickness 0.15)) (justify left bottom) hide)
    )
    (property "Manufacturer" "" (id 5) (at 330.2 130.175 0)
      (effects (font (size 1.27 1.27) (thickness 0.15)) (justify left bottom) hide)
    )
    (property "Author" "Antmicro" (id 6) (at 332.74 130.175 0)
      (effects (font (size 1.27 1.27) (thickness 0.15)) (justify left bottom) hide)
    )
    (property "License" "Apache-2.0" (id 7) (at 335.28 130.175 0)
      (effects (font (size 1.27 1.27) (thickness 0.15)) (justify left bottom) hide)
    )
    (pin "1")
  )

  (symbol (lib_id "sa800u-baseboard-hw:TP_0.75mm_SMD") (at 309.245 154.94 270) (unit 1)
    (in_bom yes) (on_board yes)
    (property "Reference" "TP39" (id 0) (at 307.594 160.274 0)
      (effects (font (size 1.27 1.27)) (justify right))
    )
    (property "Value" "TP_0.75mm_SMD" (id 1) (at 306.705 154.94 0)
      (effects (font (size 1.27 1.27)) hide)
    )
    (property "Footprint" "sa800u-baseboard-hw-footprints:TP_SMD_0.75mm" (id 2) (at 314.325 160.02 0)
      (effects (font (size 1.524 1.524)) (justify left) hide)
    )
    (property "Datasheet" "" (id 3) (at 316.865 160.02 0)
      (effects (font (size 1.524 1.524)) (justify left) hide)
    )
    (property "MPN" "" (id 4) (at 294.005 172.72 0)
      (effects (font (size 1.27 1.27) (thickness 0.15)) (justify left bottom) hide)
    )
    (property "Manufacturer" "" (id 5) (at 291.465 172.72 0)
      (effects (font (size 1.27 1.27) (thickness 0.15)) (justify left bottom) hide)
    )
    (property "Author" "Antmicro" (id 6) (at 288.925 172.72 0)
      (effects (font (size 1.27 1.27) (thickness 0.15)) (justify left bottom) hide)
    )
    (property "License" "Apache-2.0" (id 7) (at 286.385 172.72 0)
      (effects (font (size 1.27 1.27) (thickness 0.15)) (justify left bottom) hide)
    )
    (pin "1")
  )

  (symbol (lib_id "sa800u-baseboard-hw:TP_0.75mm_SMD") (at 316.23 154.94 270) (unit 1)
    (in_bom yes) (on_board yes)
    (property "Reference" "TP41" (id 0) (at 314.579 160.274 0)
      (effects (font (size 1.27 1.27)) (justify right))
    )
    (property "Value" "TP_0.75mm_SMD" (id 1) (at 313.69 154.94 0)
      (effects (font (size 1.27 1.27)) hide)
    )
    (property "Footprint" "sa800u-baseboard-hw-footprints:TP_SMD_0.75mm" (id 2) (at 321.31 160.02 0)
      (effects (font (size 1.524 1.524)) (justify left) hide)
    )
    (property "Datasheet" "" (id 3) (at 323.85 160.02 0)
      (effects (font (size 1.524 1.524)) (justify left) hide)
    )
    (property "MPN" "" (id 4) (at 300.99 172.72 0)
      (effects (font (size 1.27 1.27) (thickness 0.15)) (justify left bottom) hide)
    )
    (property "Manufacturer" "" (id 5) (at 298.45 172.72 0)
      (effects (font (size 1.27 1.27) (thickness 0.15)) (justify left bottom) hide)
    )
    (property "Author" "Antmicro" (id 6) (at 295.91 172.72 0)
      (effects (font (size 1.27 1.27) (thickness 0.15)) (justify left bottom) hide)
    )
    (property "License" "Apache-2.0" (id 7) (at 293.37 172.72 0)
      (effects (font (size 1.27 1.27) (thickness 0.15)) (justify left bottom) hide)
    )
    (pin "1")
  )

  (symbol (lib_id "sa800u-baseboard-hw:PWR_FLAG") (at 181.61 227.838 0) (unit 1)
    (in_bom yes) (on_board yes)
    (property "Reference" "#FLG0104" (id 0) (at 181.61 225.933 0)
      (effects (font (size 1.27 1.27)) hide)
    )
    (property "Value" "PWR_FLAG" (id 1) (at 181.61 222.25 0))
    (property "Footprint" "" (id 2) (at 181.61 227.838 0)
      (effects (font (size 1.27 1.27)) hide)
    )
    (property "Datasheet" "~" (id 3) (at 181.61 227.838 0)
      (effects (font (size 1.27 1.27)) hide)
    )
    (pin "1")
  )
)
